FILE_TYPE = MACRO_DRAWING;
SET COLOR_WIRE YELLOW;
SET COLOR_PROP ORANGE;
SET COLOR_DOT WHITE;
SET COLOR_ARC YELLOW;
SET COLOR_BODY GREEN;
SET COLOR_NOTE PURPLE;
SET PROP_DISPLAY VALUE;
SET PAGE_NUMBER P16;
FORCEADD GENOA_SP5..7
(-4700 3675);
FORCEPROP 1 LAST LOCATION U25
J 0
(-5345 6506);
DISPLAY 0.489362 (-5345 6506);
PAINT SKYBLUE (-5345 6506);
FORCEPROP 0 LAST $SEC 7
J 0
(-5325 6550);
DISPLAY 0.680851 (-5325 6550);
PAINT MONO (-5325 6550);
DISPLAY INVISIBLE (-5325 6550);
FORCEPROP 0 LAST CDS_SEC 7
J 0
(-5325 6525);
DISPLAY 1.021277 (-5325 6525);
DISPLAY INVISIBLE (-5325 6525);
FORCEPROP 0 LASTPIN (-5500 3050) $PN BC2
J 2
(-5510 3060);
DISPLAY 0.489362 (-5510 3060);
PAINT MONO (-5510 3060);
FORCEPROP 0 LASTPIN (-5500 3000) $PN BD2
J 2
(-5510 3010);
DISPLAY 0.489362 (-5510 3010);
PAINT MONO (-5510 3010);
FORCEPROP 0 LASTPIN (-5500 1900) $PN BF2
J 2
(-5510 1910);
DISPLAY 0.489362 (-5510 1910);
PAINT MONO (-5510 1910);
FORCEPROP 0 LASTPIN (-5500 1850) $PN BG2
J 2
(-5510 1860);
DISPLAY 0.489362 (-5510 1860);
PAINT MONO (-5510 1860);
FORCEPROP 0 LASTPIN (-5500 2200) $PN AR2
J 2
(-5510 2210);
DISPLAY 0.489362 (-5510 2210);
PAINT MONO (-5510 2210);
FORCEPROP 0 LASTPIN (-5500 2100) $PN AT2
J 2
(-5510 2110);
DISPLAY 0.489362 (-5510 2110);
PAINT MONO (-5510 2110);
FORCEPROP 0 LASTPIN (-5500 2900) $PN AU2
J 2
(-5510 2910);
DISPLAY 0.489362 (-5510 2910);
PAINT MONO (-5510 2910);
FORCEPROP 0 LASTPIN (-5500 2850) $PN AV4
J 2
(-5510 2860);
DISPLAY 0.489362 (-5510 2860);
PAINT MONO (-5510 2860);
FORCEPROP 0 LASTPIN (-5500 2750) $PN BN3
J 2
(-5510 2760);
DISPLAY 0.489362 (-5510 2760);
PAINT MONO (-5510 2760);
FORCEPROP 0 LASTPIN (-5500 1750) $PN AV2
J 2
(-5510 1760);
DISPLAY 0.489362 (-5510 1760);
PAINT MONO (-5510 1760);
FORCEPROP 0 LASTPIN (-5500 1700) $PN AW3
J 2
(-5510 1710);
DISPLAY 0.489362 (-5510 1710);
PAINT MONO (-5510 1710);
FORCEPROP 0 LASTPIN (-5500 1600) $PN BP4
J 2
(-5510 1610);
DISPLAY 0.489362 (-5510 1610);
PAINT MONO (-5510 1610);
FORCEPROP 0 LASTPIN (-5500 3900) $PN AW2
J 2
(-5510 3910);
DISPLAY 0.489362 (-5510 3910);
PAINT MONO (-5510 3910);
FORCEPROP 0 LASTPIN (-5500 3850) $PN AY2
J 2
(-5510 3860);
DISPLAY 0.489362 (-5510 3860);
PAINT MONO (-5510 3860);
FORCEPROP 0 LASTPIN (-5500 3800) $PN AY4
J 2
(-5510 3810);
DISPLAY 0.489362 (-5510 3810);
PAINT MONO (-5510 3810);
FORCEPROP 0 LASTPIN (-5500 3750) $PN BA3
J 2
(-5510 3760);
DISPLAY 0.489362 (-5510 3760);
PAINT MONO (-5510 3760);
FORCEPROP 0 LASTPIN (-5500 3700) $PN BA2
J 2
(-5510 3710);
DISPLAY 0.489362 (-5510 3710);
PAINT MONO (-5510 3710);
FORCEPROP 0 LASTPIN (-5500 3650) $PN BB2
J 2
(-5510 3660);
DISPLAY 0.489362 (-5510 3660);
PAINT MONO (-5510 3660);
FORCEPROP 0 LASTPIN (-5500 3600) $PN BB4
J 2
(-5510 3610);
DISPLAY 0.489362 (-5510 3610);
PAINT MONO (-5510 3610);
FORCEPROP 0 LASTPIN (-3900 2450) $PN AJ2
J 0
(-3890 2460);
DISPLAY 0.489362 (-3890 2460);
PAINT MONO (-3890 2460);
FORCEPROP 0 LASTPIN (-3900 2400) $PN AK4
J 0
(-3890 2410);
DISPLAY 0.489362 (-3890 2410);
PAINT MONO (-3890 2410);
FORCEPROP 0 LASTPIN (-3900 2350) $PN AK2
J 0
(-3890 2360);
DISPLAY 0.489362 (-3890 2360);
PAINT MONO (-3890 2360);
FORCEPROP 0 LASTPIN (-3900 2300) $PN AL3
J 0
(-3890 2310);
DISPLAY 0.489362 (-3890 2310);
PAINT MONO (-3890 2310);
FORCEPROP 0 LASTPIN (-3900 2250) $PN AN2
J 0
(-3890 2260);
DISPLAY 0.489362 (-3890 2260);
PAINT MONO (-3890 2260);
FORCEPROP 0 LASTPIN (-3900 2200) $PN AP4
J 0
(-3890 2210);
DISPLAY 0.489362 (-3890 2210);
PAINT MONO (-3890 2210);
FORCEPROP 0 LASTPIN (-3900 2150) $PN AP2
J 0
(-3890 2160);
DISPLAY 0.489362 (-3890 2160);
PAINT MONO (-3890 2160);
FORCEPROP 0 LASTPIN (-3900 2100) $PN AR3
J 0
(-3890 2110);
DISPLAY 0.489362 (-3890 2110);
PAINT MONO (-3890 2110);
FORCEPROP 0 LASTPIN (-3900 6050) $PN E2
J 0
(-3890 6060);
DISPLAY 0.489362 (-3890 6060);
PAINT MONO (-3890 6060);
FORCEPROP 0 LASTPIN (-3900 6000) $PN F4
J 0
(-3890 6010);
DISPLAY 0.489362 (-3890 6010);
PAINT MONO (-3890 6010);
FORCEPROP 0 LASTPIN (-3900 5950) $PN F2
J 0
(-3890 5960);
DISPLAY 0.489362 (-3890 5960);
PAINT MONO (-3890 5960);
FORCEPROP 0 LASTPIN (-3900 5900) $PN G3
J 0
(-3890 5910);
DISPLAY 0.489362 (-3890 5910);
PAINT MONO (-3890 5910);
FORCEPROP 0 LASTPIN (-3900 5850) $PN J2
J 0
(-3890 5860);
DISPLAY 0.489362 (-3890 5860);
PAINT MONO (-3890 5860);
FORCEPROP 0 LASTPIN (-3900 5800) $PN K4
J 0
(-3890 5810);
DISPLAY 0.489362 (-3890 5810);
PAINT MONO (-3890 5810);
FORCEPROP 0 LASTPIN (-3900 5750) $PN K2
J 0
(-3890 5760);
DISPLAY 0.489362 (-3890 5760);
PAINT MONO (-3890 5760);
FORCEPROP 0 LASTPIN (-3900 5700) $PN L3
J 0
(-3890 5710);
DISPLAY 0.489362 (-3890 5710);
PAINT MONO (-3890 5710);
FORCEPROP 0 LASTPIN (-3900 5600) $PN L2
J 0
(-3890 5610);
DISPLAY 0.489362 (-3890 5610);
PAINT MONO (-3890 5610);
FORCEPROP 0 LASTPIN (-3900 5550) $PN M4
J 0
(-3890 5560);
DISPLAY 0.489362 (-3890 5560);
PAINT MONO (-3890 5560);
FORCEPROP 0 LASTPIN (-3900 5500) $PN M2
J 0
(-3890 5510);
DISPLAY 0.489362 (-3890 5510);
PAINT MONO (-3890 5510);
FORCEPROP 0 LASTPIN (-3900 5450) $PN N3
J 0
(-3890 5460);
DISPLAY 0.489362 (-3890 5460);
PAINT MONO (-3890 5460);
FORCEPROP 0 LASTPIN (-3900 5400) $PN R2
J 0
(-3890 5410);
DISPLAY 0.489362 (-3890 5410);
PAINT MONO (-3890 5410);
FORCEPROP 0 LASTPIN (-3900 5350) $PN T4
J 0
(-3890 5360);
DISPLAY 0.489362 (-3890 5360);
PAINT MONO (-3890 5360);
FORCEPROP 0 LASTPIN (-3900 5300) $PN T2
J 0
(-3890 5310);
DISPLAY 0.489362 (-3890 5310);
PAINT MONO (-3890 5310);
FORCEPROP 0 LASTPIN (-3900 5250) $PN U3
J 0
(-3890 5260);
DISPLAY 0.489362 (-3890 5260);
PAINT MONO (-3890 5260);
FORCEPROP 0 LASTPIN (-3900 5150) $PN U2
J 0
(-3890 5160);
DISPLAY 0.489362 (-3890 5160);
PAINT MONO (-3890 5160);
FORCEPROP 0 LASTPIN (-3900 5100) $PN V4
J 0
(-3890 5110);
DISPLAY 0.489362 (-3890 5110);
PAINT MONO (-3890 5110);
FORCEPROP 0 LASTPIN (-3900 5050) $PN V2
J 0
(-3890 5060);
DISPLAY 0.489362 (-3890 5060);
PAINT MONO (-3890 5060);
FORCEPROP 0 LASTPIN (-3900 5000) $PN W3
J 0
(-3890 5010);
DISPLAY 0.489362 (-3890 5010);
PAINT MONO (-3890 5010);
FORCEPROP 0 LASTPIN (-3900 4950) $PN AA2
J 0
(-3890 4960);
DISPLAY 0.489362 (-3890 4960);
PAINT MONO (-3890 4960);
FORCEPROP 0 LASTPIN (-3900 4900) $PN AB4
J 0
(-3890 4910);
DISPLAY 0.489362 (-3890 4910);
PAINT MONO (-3890 4910);
FORCEPROP 0 LASTPIN (-3900 4850) $PN AB2
J 0
(-3890 4860);
DISPLAY 0.489362 (-3890 4860);
PAINT MONO (-3890 4860);
FORCEPROP 0 LASTPIN (-3900 4800) $PN AC3
J 0
(-3890 4810);
DISPLAY 0.489362 (-3890 4810);
PAINT MONO (-3890 4810);
FORCEPROP 0 LASTPIN (-3900 4700) $PN AC2
J 0
(-3890 4710);
DISPLAY 0.489362 (-3890 4710);
PAINT MONO (-3890 4710);
FORCEPROP 0 LASTPIN (-3900 4650) $PN AD4
J 0
(-3890 4660);
DISPLAY 0.489362 (-3890 4660);
PAINT MONO (-3890 4660);
FORCEPROP 0 LASTPIN (-3900 4600) $PN AD2
J 0
(-3890 4610);
DISPLAY 0.489362 (-3890 4610);
PAINT MONO (-3890 4610);
FORCEPROP 0 LASTPIN (-3900 4550) $PN AE3
J 0
(-3890 4560);
DISPLAY 0.489362 (-3890 4560);
PAINT MONO (-3890 4560);
FORCEPROP 0 LASTPIN (-3900 4500) $PN AG2
J 0
(-3890 4510);
DISPLAY 0.489362 (-3890 4510);
PAINT MONO (-3890 4510);
FORCEPROP 0 LASTPIN (-3900 4450) $PN AH4
J 0
(-3890 4460);
DISPLAY 0.489362 (-3890 4460);
PAINT MONO (-3890 4460);
FORCEPROP 0 LASTPIN (-3900 4400) $PN AH2
J 0
(-3890 4410);
DISPLAY 0.489362 (-3890 4410);
PAINT MONO (-3890 4410);
FORCEPROP 0 LASTPIN (-3900 4350) $PN AJ3
J 0
(-3890 4360);
DISPLAY 0.489362 (-3890 4360);
PAINT MONO (-3890 4360);
FORCEPROP 0 LASTPIN (-5500 6050) $PN G2
J 2
(-5510 6060);
DISPLAY 0.489362 (-5510 6060);
PAINT MONO (-5510 6060);
FORCEPROP 0 LASTPIN (-5500 5950) $PN N2
J 2
(-5510 5960);
DISPLAY 0.489362 (-5510 5960);
PAINT MONO (-5510 5960);
FORCEPROP 0 LASTPIN (-5500 5850) $PN W2
J 2
(-5510 5860);
DISPLAY 0.489362 (-5510 5860);
PAINT MONO (-5510 5860);
FORCEPROP 0 LASTPIN (-5500 5750) $PN AE2
J 2
(-5510 5760);
DISPLAY 0.489362 (-5510 5760);
PAINT MONO (-5510 5760);
FORCEPROP 0 LASTPIN (-5500 5650) $PN AL2
J 2
(-5510 5660);
DISPLAY 0.489362 (-5510 5660);
PAINT MONO (-5510 5660);
FORCEPROP 0 LASTPIN (-5500 5550) $PN J3
J 2
(-5510 5560);
DISPLAY 0.489362 (-5510 5560);
PAINT MONO (-5510 5560);
FORCEPROP 0 LASTPIN (-5500 5450) $PN R3
J 2
(-5510 5460);
DISPLAY 0.489362 (-5510 5460);
PAINT MONO (-5510 5460);
FORCEPROP 0 LASTPIN (-5500 5350) $PN AA3
J 2
(-5510 5360);
DISPLAY 0.489362 (-5510 5360);
PAINT MONO (-5510 5360);
FORCEPROP 0 LASTPIN (-5500 5250) $PN AG3
J 2
(-5510 5260);
DISPLAY 0.489362 (-5510 5260);
PAINT MONO (-5510 5260);
FORCEPROP 0 LASTPIN (-5500 5150) $PN AN3
J 2
(-5510 5160);
DISPLAY 0.489362 (-5510 5160);
PAINT MONO (-5510 5160);
FORCEPROP 0 LASTPIN (-5500 6000) $PN H2
J 2
(-5510 6010);
DISPLAY 0.489362 (-5510 6010);
PAINT MONO (-5510 6010);
FORCEPROP 0 LASTPIN (-5500 5900) $PN P2
J 2
(-5510 5910);
DISPLAY 0.489362 (-5510 5910);
PAINT MONO (-5510 5910);
FORCEPROP 0 LASTPIN (-5500 5800) $PN Y2
J 2
(-5510 5810);
DISPLAY 0.489362 (-5510 5810);
PAINT MONO (-5510 5810);
FORCEPROP 0 LASTPIN (-5500 5700) $PN AF2
J 2
(-5510 5710);
DISPLAY 0.489362 (-5510 5710);
PAINT MONO (-5510 5710);
FORCEPROP 0 LASTPIN (-5500 5600) $PN AM2
J 2
(-5510 5610);
DISPLAY 0.489362 (-5510 5610);
PAINT MONO (-5510 5610);
FORCEPROP 0 LASTPIN (-5500 5500) $PN H4
J 2
(-5510 5510);
DISPLAY 0.489362 (-5510 5510);
PAINT MONO (-5510 5510);
FORCEPROP 0 LASTPIN (-5500 5400) $PN P4
J 2
(-5510 5410);
DISPLAY 0.489362 (-5510 5410);
PAINT MONO (-5510 5410);
FORCEPROP 0 LASTPIN (-5500 5300) $PN Y4
J 2
(-5510 5310);
DISPLAY 0.489362 (-5510 5310);
PAINT MONO (-5510 5310);
FORCEPROP 0 LASTPIN (-5500 5200) $PN AF4
J 2
(-5510 5210);
DISPLAY 0.489362 (-5510 5210);
PAINT MONO (-5510 5210);
FORCEPROP 0 LASTPIN (-5500 5100) $PN AM4
J 2
(-5510 5110);
DISPLAY 0.489362 (-5510 5110);
PAINT MONO (-5510 5110);
FORCEPROP 0 LASTPIN (-5500 2650) $PN BC3
J 2
(-5510 2660);
DISPLAY 0.489362 (-5510 2660);
PAINT MONO (-5510 2660);
FORCEPROP 0 LASTPIN (-5500 2550) $PN BM4
J 2
(-5510 2560);
DISPLAY 0.489362 (-5510 2560);
PAINT MONO (-5510 2560);
FORCEPROP 0 LASTPIN (-5500 2500) $PN BN2
J 2
(-5510 2510);
DISPLAY 0.489362 (-5510 2510);
PAINT MONO (-5510 2510);
FORCEPROP 0 LASTPIN (-5500 2400) $PN BP2
J 2
(-5510 2410);
DISPLAY 0.489362 (-5510 2410);
PAINT MONO (-5510 2410);
FORCEPROP 0 LASTPIN (-5500 1500) $PN BL2
J 2
(-5510 1510);
DISPLAY 0.489362 (-5510 1510);
PAINT MONO (-5510 1510);
FORCEPROP 0 LASTPIN (-5500 1450) $PN BM2
J 2
(-5510 1460);
DISPLAY 0.489362 (-5510 1460);
PAINT MONO (-5510 1460);
FORCEPROP 0 LASTPIN (-5500 1350) $PN BR2
J 2
(-5510 1360);
DISPLAY 0.489362 (-5510 1360);
PAINT MONO (-5510 1360);
FORCEPROP 0 LASTPIN (-5500 3500) $PN BG3
J 2
(-5510 3510);
DISPLAY 0.489362 (-5510 3510);
PAINT MONO (-5510 3510);
FORCEPROP 0 LASTPIN (-5500 3450) $PN BH4
J 2
(-5510 3460);
DISPLAY 0.489362 (-5510 3460);
PAINT MONO (-5510 3460);
FORCEPROP 0 LASTPIN (-5500 3400) $PN BH2
J 2
(-5510 3410);
DISPLAY 0.489362 (-5510 3410);
PAINT MONO (-5510 3410);
FORCEPROP 0 LASTPIN (-5500 3350) $PN BJ2
J 2
(-5510 3360);
DISPLAY 0.489362 (-5510 3360);
PAINT MONO (-5510 3360);
FORCEPROP 0 LASTPIN (-5500 3300) $PN BJ3
J 2
(-5510 3310);
DISPLAY 0.489362 (-5510 3310);
PAINT MONO (-5510 3310);
FORCEPROP 0 LASTPIN (-5500 3250) $PN BK4
J 2
(-5510 3260);
DISPLAY 0.489362 (-5510 3260);
PAINT MONO (-5510 3260);
FORCEPROP 0 LASTPIN (-5500 3200) $PN BK2
J 2
(-5510 3210);
DISPLAY 0.489362 (-5510 3210);
PAINT MONO (-5510 3210);
FORCEPROP 0 LASTPIN (-3900 2000) $PN BY2
J 0
(-3890 2010);
DISPLAY 0.489362 (-3890 2010);
PAINT MONO (-3890 2010);
FORCEPROP 0 LASTPIN (-3900 1950) $PN CA3
J 0
(-3890 1960);
DISPLAY 0.489362 (-3890 1960);
PAINT MONO (-3890 1960);
FORCEPROP 0 LASTPIN (-3900 1900) $PN CA2
J 0
(-3890 1910);
DISPLAY 0.489362 (-3890 1910);
PAINT MONO (-3890 1910);
FORCEPROP 0 LASTPIN (-3900 1850) $PN CB4
J 0
(-3890 1860);
DISPLAY 0.489362 (-3890 1860);
PAINT MONO (-3890 1860);
FORCEPROP 0 LASTPIN (-3900 1800) $PN BT2
J 0
(-3890 1810);
DISPLAY 0.489362 (-3890 1810);
PAINT MONO (-3890 1810);
FORCEPROP 0 LASTPIN (-3900 1750) $PN BU3
J 0
(-3890 1760);
DISPLAY 0.489362 (-3890 1760);
PAINT MONO (-3890 1760);
FORCEPROP 0 LASTPIN (-3900 1700) $PN BU2
J 0
(-3890 1710);
DISPLAY 0.489362 (-3890 1710);
PAINT MONO (-3890 1710);
FORCEPROP 0 LASTPIN (-3900 1650) $PN BV4
J 0
(-3890 1660);
DISPLAY 0.489362 (-3890 1660);
PAINT MONO (-3890 1660);
FORCEPROP 0 LASTPIN (-3900 4250) $PN CB2
J 0
(-3890 4260);
DISPLAY 0.489362 (-3890 4260);
PAINT MONO (-3890 4260);
FORCEPROP 0 LASTPIN (-3900 4200) $PN CC3
J 0
(-3890 4210);
DISPLAY 0.489362 (-3890 4210);
PAINT MONO (-3890 4210);
FORCEPROP 0 LASTPIN (-3900 4150) $PN CC2
J 0
(-3890 4160);
DISPLAY 0.489362 (-3890 4160);
PAINT MONO (-3890 4160);
FORCEPROP 0 LASTPIN (-3900 4100) $PN CD4
J 0
(-3890 4110);
DISPLAY 0.489362 (-3890 4110);
PAINT MONO (-3890 4110);
FORCEPROP 0 LASTPIN (-3900 4050) $PN CF2
J 0
(-3890 4060);
DISPLAY 0.489362 (-3890 4060);
PAINT MONO (-3890 4060);
FORCEPROP 0 LASTPIN (-3900 4000) $PN CG3
J 0
(-3890 4010);
DISPLAY 0.489362 (-3890 4010);
PAINT MONO (-3890 4010);
FORCEPROP 0 LASTPIN (-3900 3950) $PN CG2
J 0
(-3890 3960);
DISPLAY 0.489362 (-3890 3960);
PAINT MONO (-3890 3960);
FORCEPROP 0 LASTPIN (-3900 3900) $PN CH4
J 0
(-3890 3910);
DISPLAY 0.489362 (-3890 3910);
PAINT MONO (-3890 3910);
FORCEPROP 0 LASTPIN (-3900 3800) $PN CH2
J 0
(-3890 3810);
DISPLAY 0.489362 (-3890 3810);
PAINT MONO (-3890 3810);
FORCEPROP 0 LASTPIN (-3900 3750) $PN CJ3
J 0
(-3890 3760);
DISPLAY 0.489362 (-3890 3760);
PAINT MONO (-3890 3760);
FORCEPROP 0 LASTPIN (-3900 3700) $PN CJ2
J 0
(-3890 3710);
DISPLAY 0.489362 (-3890 3710);
PAINT MONO (-3890 3710);
FORCEPROP 0 LASTPIN (-3900 3650) $PN CK4
J 0
(-3890 3660);
DISPLAY 0.489362 (-3890 3660);
PAINT MONO (-3890 3660);
FORCEPROP 0 LASTPIN (-3900 3600) $PN CM2
J 0
(-3890 3610);
DISPLAY 0.489362 (-3890 3610);
PAINT MONO (-3890 3610);
FORCEPROP 0 LASTPIN (-3900 3550) $PN CN3
J 0
(-3890 3560);
DISPLAY 0.489362 (-3890 3560);
PAINT MONO (-3890 3560);
FORCEPROP 0 LASTPIN (-3900 3500) $PN CN2
J 0
(-3890 3510);
DISPLAY 0.489362 (-3890 3510);
PAINT MONO (-3890 3510);
FORCEPROP 0 LASTPIN (-3900 3450) $PN CP4
J 0
(-3890 3460);
DISPLAY 0.489362 (-3890 3460);
PAINT MONO (-3890 3460);
FORCEPROP 0 LASTPIN (-3900 3350) $PN CP2
J 0
(-3890 3360);
DISPLAY 0.489362 (-3890 3360);
PAINT MONO (-3890 3360);
FORCEPROP 0 LASTPIN (-3900 3300) $PN CR3
J 0
(-3890 3310);
DISPLAY 0.489362 (-3890 3310);
PAINT MONO (-3890 3310);
FORCEPROP 0 LASTPIN (-3900 3250) $PN CR2
J 0
(-3890 3260);
DISPLAY 0.489362 (-3890 3260);
PAINT MONO (-3890 3260);
FORCEPROP 0 LASTPIN (-3900 3200) $PN CT4
J 0
(-3890 3210);
DISPLAY 0.489362 (-3890 3210);
PAINT MONO (-3890 3210);
FORCEPROP 0 LASTPIN (-3900 3150) $PN CV2
J 0
(-3890 3160);
DISPLAY 0.489362 (-3890 3160);
PAINT MONO (-3890 3160);
FORCEPROP 0 LASTPIN (-3900 3100) $PN CW3
J 0
(-3890 3110);
DISPLAY 0.489362 (-3890 3110);
PAINT MONO (-3890 3110);
FORCEPROP 0 LASTPIN (-3900 3050) $PN CW2
J 0
(-3890 3060);
DISPLAY 0.489362 (-3890 3060);
PAINT MONO (-3890 3060);
FORCEPROP 0 LASTPIN (-3900 3000) $PN CY4
J 0
(-3890 3010);
DISPLAY 0.489362 (-3890 3010);
PAINT MONO (-3890 3010);
FORCEPROP 0 LASTPIN (-3900 2900) $PN CY2
J 0
(-3890 2910);
DISPLAY 0.489362 (-3890 2910);
PAINT MONO (-3890 2910);
FORCEPROP 0 LASTPIN (-3900 2850) $PN DA3
J 0
(-3890 2860);
DISPLAY 0.489362 (-3890 2860);
PAINT MONO (-3890 2860);
FORCEPROP 0 LASTPIN (-3900 2800) $PN DA2
J 0
(-3890 2810);
DISPLAY 0.489362 (-3890 2810);
PAINT MONO (-3890 2810);
FORCEPROP 0 LASTPIN (-3900 2750) $PN DB4
J 0
(-3890 2760);
DISPLAY 0.489362 (-3890 2760);
PAINT MONO (-3890 2760);
FORCEPROP 0 LASTPIN (-3900 2700) $PN DD2
J 0
(-3890 2710);
DISPLAY 0.489362 (-3890 2710);
PAINT MONO (-3890 2710);
FORCEPROP 0 LASTPIN (-3900 2650) $PN DE3
J 0
(-3890 2660);
DISPLAY 0.489362 (-3890 2660);
PAINT MONO (-3890 2660);
FORCEPROP 0 LASTPIN (-3900 2600) $PN DE2
J 0
(-3890 2610);
DISPLAY 0.489362 (-3890 2610);
PAINT MONO (-3890 2610);
FORCEPROP 0 LASTPIN (-3900 2550) $PN DF2
J 0
(-3890 2560);
DISPLAY 0.489362 (-3890 2560);
PAINT MONO (-3890 2560);
FORCEPROP 0 LASTPIN (-5500 5000) $PN CD2
J 2
(-5510 5010);
DISPLAY 0.489362 (-5510 5010);
PAINT MONO (-5510 5010);
FORCEPROP 0 LASTPIN (-5500 4900) $PN CK2
J 2
(-5510 4910);
DISPLAY 0.489362 (-5510 4910);
PAINT MONO (-5510 4910);
FORCEPROP 0 LASTPIN (-5500 4800) $PN CT2
J 2
(-5510 4810);
DISPLAY 0.489362 (-5510 4810);
PAINT MONO (-5510 4810);
FORCEPROP 0 LASTPIN (-5500 4700) $PN DB2
J 2
(-5510 4710);
DISPLAY 0.489362 (-5510 4710);
PAINT MONO (-5510 4710);
FORCEPROP 0 LASTPIN (-5500 4600) $PN BY4
J 2
(-5510 4610);
DISPLAY 0.489362 (-5510 4610);
PAINT MONO (-5510 4610);
FORCEPROP 0 LASTPIN (-5500 4500) $PN CF4
J 2
(-5510 4510);
DISPLAY 0.489362 (-5510 4510);
PAINT MONO (-5510 4510);
FORCEPROP 0 LASTPIN (-5500 4400) $PN CM4
J 2
(-5510 4410);
DISPLAY 0.489362 (-5510 4410);
PAINT MONO (-5510 4410);
FORCEPROP 0 LASTPIN (-5500 4300) $PN CV4
J 2
(-5510 4310);
DISPLAY 0.489362 (-5510 4310);
PAINT MONO (-5510 4310);
FORCEPROP 0 LASTPIN (-5500 4200) $PN DD4
J 2
(-5510 4210);
DISPLAY 0.489362 (-5510 4210);
PAINT MONO (-5510 4210);
FORCEPROP 0 LASTPIN (-5500 4100) $PN BV2
J 2
(-5510 4110);
DISPLAY 0.489362 (-5510 4110);
PAINT MONO (-5510 4110);
FORCEPROP 0 LASTPIN (-5500 4950) $PN CE2
J 2
(-5510 4960);
DISPLAY 0.489362 (-5510 4960);
PAINT MONO (-5510 4960);
FORCEPROP 0 LASTPIN (-5500 4850) $PN CL2
J 2
(-5510 4860);
DISPLAY 0.489362 (-5510 4860);
PAINT MONO (-5510 4860);
FORCEPROP 0 LASTPIN (-5500 4750) $PN CU2
J 2
(-5510 4760);
DISPLAY 0.489362 (-5510 4760);
PAINT MONO (-5510 4760);
FORCEPROP 0 LASTPIN (-5500 4650) $PN DC2
J 2
(-5510 4660);
DISPLAY 0.489362 (-5510 4660);
PAINT MONO (-5510 4660);
FORCEPROP 0 LASTPIN (-5500 4550) $PN BW3
J 2
(-5510 4560);
DISPLAY 0.489362 (-5510 4560);
PAINT MONO (-5510 4560);
FORCEPROP 0 LASTPIN (-5500 4450) $PN CE3
J 2
(-5510 4460);
DISPLAY 0.489362 (-5510 4460);
PAINT MONO (-5510 4460);
FORCEPROP 0 LASTPIN (-5500 4350) $PN CL3
J 2
(-5510 4360);
DISPLAY 0.489362 (-5510 4360);
PAINT MONO (-5510 4360);
FORCEPROP 0 LASTPIN (-5500 4250) $PN CU3
J 2
(-5510 4260);
DISPLAY 0.489362 (-5510 4260);
PAINT MONO (-5510 4260);
FORCEPROP 0 LASTPIN (-5500 4150) $PN DC3
J 2
(-5510 4160);
DISPLAY 0.489362 (-5510 4160);
PAINT MONO (-5510 4160);
FORCEPROP 0 LASTPIN (-5500 4050) $PN BW2
J 2
(-5510 4060);
DISPLAY 0.489362 (-5510 4060);
PAINT MONO (-5510 4060);
FORCEPROP 0 LASTPIN (-5500 2300) $PN BL3
J 2
(-5510 2310);
DISPLAY 0.489362 (-5510 2310);
PAINT MONO (-5510 2310);
FORCEPROP 0 LASTPIN (-5500 1250) $PN BF4
J 2
(-5510 1260);
DISPLAY 0.489362 (-5510 1260);
PAINT MONO (-5510 1260);
FORCEPROP 2 LAST PART_TYPE SMLF
J 0
(-5325 6455);
DISPLAY 1.021277 (-5325 6455);
FORCEPROP 1 LAST MATERIAL IO
J 0
(-5345 6232);
DISPLAY 0.489362 (-5345 6232);
PAINT SKYBLUE (-5345 6232);
FORCEPROP 2 LAST VALUE SOCKET6096_13568-001
J 0
(-5325 6355);
DISPLAY 0.489362 (-5325 6355);
PAINT SKYBLUE (-5325 6355);
FORCEPROP 2 LAST CDS_LIB pure_quanta
J 0
(-4700 3675);
DISPLAY INVISIBLE (-4700 3675);
FORCEPROP 1 LAST CDS_LMAN_SYM_OUTLINE -650,2525,650,-2525
J 0
(-4700 3675);
DISPLAY 0.468085 (-4700 3675);
PAINT GREEN (-4700 3675);
DISPLAY INVISIBLE (-4700 3675);
FORCEPROP 1 LAST NEEDS_NO_SIZE TRUE
J 0
(-4700 3675);
DISPLAY 0.723404 (-4700 3675);
PAINT GREEN (-4700 3675);
DISPLAY INVISIBLE (-4700 3675);
FORCEPROP 1 LAST PATH I167
J 0
(-4700 3675);
DISPLAY 0.723404 (-4700 3675);
PAINT GREEN (-4700 3675);
DISPLAY INVISIBLE (-4700 3675);
FORCEPROP 1 LAST PART_NUMBER DGA^6000030
J 0
(-5345 6359);
DISPLAY 0.489362 (-5345 6359);
PAINT SKYBLUE (-5345 6359);
DISPLAY INVISIBLE (-5345 6359);
FORCEADD OFFPAGE..3
(-2700 6075);
FORCEPROP 2 LAST $XR0 92 
J 0
(-2486 6075);
DISPLAY 0.638298 (-2486 6075);
PAINT MONO (-2486 6075);
FORCEPROP 2 LAST CDS_LIB mstr_standard
J 0
(-2700 6075);
DISPLAY 0.723404 (-2700 6075);
PAINT MONO (-2700 6075);
DISPLAY INVISIBLE (-2700 6075);
FORCEPROP 1 LAST OFFPAGE TRUE
J 0
(-2375 5950);
DISPLAY 0.872340 (-2375 5950);
PAINT GREEN (-2375 5950);
DISPLAY INVISIBLE (-2375 5950);
FORCEPROP 1 LAST COMMENT_BODY TRUE
J 0
(-2750 5975);
DISPLAY 0.872340 (-2750 5975);
PAINT GREEN (-2750 5975);
DISPLAY INVISIBLE (-2750 5975);
FORCEPROP 2 LAST PATH I168
J 0
(-2475 6125);
DISPLAY 1.021277 (-2475 6125);
DISPLAY INVISIBLE (-2475 6125);
FORCEADD OFFPAGE..3
(-2700 4275);
FORCEPROP 2 LAST $XR0 92 
J 0
(-2486 4275);
DISPLAY 0.638298 (-2486 4275);
PAINT MONO (-2486 4275);
FORCEPROP 2 LAST CDS_LIB mstr_standard
J 0
(-2700 4275);
DISPLAY 0.723404 (-2700 4275);
PAINT MONO (-2700 4275);
DISPLAY INVISIBLE (-2700 4275);
FORCEPROP 1 LAST OFFPAGE TRUE
J 0
(-2375 4150);
DISPLAY 0.872340 (-2375 4150);
PAINT GREEN (-2375 4150);
DISPLAY INVISIBLE (-2375 4150);
FORCEPROP 1 LAST COMMENT_BODY TRUE
J 0
(-2750 4175);
DISPLAY 0.872340 (-2750 4175);
PAINT GREEN (-2750 4175);
DISPLAY INVISIBLE (-2750 4175);
FORCEPROP 2 LAST PATH I169
J 0
(-2475 4325);
DISPLAY 1.021277 (-2475 4325);
DISPLAY INVISIBLE (-2475 4325);
FORCEADD TAP..1
(-3425 6050);
FORCEPROP 3 LASTPIN (-3475 6050) SIG_NAME M_G_CPU0_SA_DQ<0>
J 0
(-3465 6060);
DISPLAY 0.659574 (-3465 6060);
PAINT MONO (-3465 6060);
DISPLAY INVISIBLE (-3465 6060);
FORCEPROP 1 LASTPIN (-3475 6050) BN 0
J 0
(-3487 6058);
DISPLAY 0.489362 (-3487 6058);
PAINT GREEN (-3487 6058);
FORCEPROP 2 LAST CDS_LIB mstr_standard
J 0
(-3425 6050);
DISPLAY 0.723404 (-3425 6050);
PAINT MONO (-3425 6050);
DISPLAY INVISIBLE (-3425 6050);
FORCEPROP 1 LAST BODY_TYPE PLUMBING
J 0
(-3425 6100);
DISPLAY 0.872340 (-3425 6100);
PAINT GREEN (-3425 6100);
DISPLAY INVISIBLE (-3425 6100);
FORCEPROP 1 LAST HDL_TAP TRUE
J 0
(-3100 5925);
DISPLAY 0.872340 (-3100 5925);
DISPLAY INVISIBLE (-3100 5925);
FORCEPROP 1 LAST PATH I170
J 0
(-3427 6050);
DISPLAY 0.872340 (-3427 6050);
PAINT GREEN (-3427 6050);
DISPLAY INVISIBLE (-3427 6050);
FORCEADD TAP..1
(-3425 6000);
FORCEPROP 3 LASTPIN (-3475 6000) SIG_NAME M_G_CPU0_SA_DQ<1>
J 0
(-3465 6010);
DISPLAY 0.659574 (-3465 6010);
PAINT MONO (-3465 6010);
DISPLAY INVISIBLE (-3465 6010);
FORCEPROP 1 LASTPIN (-3475 6000) BN 1
J 0
(-3487 6008);
DISPLAY 0.489362 (-3487 6008);
PAINT GREEN (-3487 6008);
FORCEPROP 2 LAST CDS_LIB mstr_standard
J 0
(-3425 6000);
DISPLAY 0.723404 (-3425 6000);
PAINT MONO (-3425 6000);
DISPLAY INVISIBLE (-3425 6000);
FORCEPROP 1 LAST BODY_TYPE PLUMBING
J 0
(-3425 6050);
DISPLAY 0.872340 (-3425 6050);
PAINT GREEN (-3425 6050);
DISPLAY INVISIBLE (-3425 6050);
FORCEPROP 1 LAST HDL_TAP TRUE
J 0
(-3100 5875);
DISPLAY 0.872340 (-3100 5875);
DISPLAY INVISIBLE (-3100 5875);
FORCEPROP 1 LAST PATH I171
J 0
(-3427 6000);
DISPLAY 0.872340 (-3427 6000);
PAINT GREEN (-3427 6000);
DISPLAY INVISIBLE (-3427 6000);
FORCEADD TAP..1
(-3425 5950);
FORCEPROP 3 LASTPIN (-3475 5950) SIG_NAME M_G_CPU0_SA_DQ<2>
J 0
(-3465 5960);
DISPLAY 0.659574 (-3465 5960);
PAINT MONO (-3465 5960);
DISPLAY INVISIBLE (-3465 5960);
FORCEPROP 1 LASTPIN (-3475 5950) BN 2
J 0
(-3487 5958);
DISPLAY 0.489362 (-3487 5958);
PAINT GREEN (-3487 5958);
FORCEPROP 2 LAST CDS_LIB mstr_standard
J 0
(-3425 5950);
DISPLAY 0.723404 (-3425 5950);
PAINT MONO (-3425 5950);
DISPLAY INVISIBLE (-3425 5950);
FORCEPROP 1 LAST BODY_TYPE PLUMBING
J 0
(-3425 6000);
DISPLAY 0.872340 (-3425 6000);
PAINT GREEN (-3425 6000);
DISPLAY INVISIBLE (-3425 6000);
FORCEPROP 1 LAST HDL_TAP TRUE
J 0
(-3100 5825);
DISPLAY 0.872340 (-3100 5825);
DISPLAY INVISIBLE (-3100 5825);
FORCEPROP 1 LAST PATH I172
J 0
(-3427 5950);
DISPLAY 0.872340 (-3427 5950);
PAINT GREEN (-3427 5950);
DISPLAY INVISIBLE (-3427 5950);
FORCEADD TAP..1
(-3425 5900);
FORCEPROP 3 LASTPIN (-3475 5900) SIG_NAME M_G_CPU0_SA_DQ<3>
J 0
(-3465 5910);
DISPLAY 0.659574 (-3465 5910);
PAINT MONO (-3465 5910);
DISPLAY INVISIBLE (-3465 5910);
FORCEPROP 1 LASTPIN (-3475 5900) BN 3
J 0
(-3487 5908);
DISPLAY 0.489362 (-3487 5908);
PAINT GREEN (-3487 5908);
FORCEPROP 2 LAST CDS_LIB mstr_standard
J 0
(-3425 5900);
DISPLAY 0.723404 (-3425 5900);
PAINT MONO (-3425 5900);
DISPLAY INVISIBLE (-3425 5900);
FORCEPROP 1 LAST BODY_TYPE PLUMBING
J 0
(-3425 5950);
DISPLAY 0.872340 (-3425 5950);
PAINT GREEN (-3425 5950);
DISPLAY INVISIBLE (-3425 5950);
FORCEPROP 1 LAST HDL_TAP TRUE
J 0
(-3100 5775);
DISPLAY 0.872340 (-3100 5775);
DISPLAY INVISIBLE (-3100 5775);
FORCEPROP 1 LAST PATH I173
J 0
(-3427 5900);
DISPLAY 0.872340 (-3427 5900);
PAINT GREEN (-3427 5900);
DISPLAY INVISIBLE (-3427 5900);
FORCEADD TAP..1
(-3425 5850);
FORCEPROP 3 LASTPIN (-3475 5850) SIG_NAME M_G_CPU0_SA_DQ<4>
J 0
(-3465 5860);
DISPLAY 0.659574 (-3465 5860);
PAINT MONO (-3465 5860);
DISPLAY INVISIBLE (-3465 5860);
FORCEPROP 1 LASTPIN (-3475 5850) BN 4
J 0
(-3487 5858);
DISPLAY 0.489362 (-3487 5858);
PAINT GREEN (-3487 5858);
FORCEPROP 2 LAST CDS_LIB mstr_standard
J 0
(-3425 5850);
DISPLAY 0.723404 (-3425 5850);
PAINT MONO (-3425 5850);
DISPLAY INVISIBLE (-3425 5850);
FORCEPROP 1 LAST BODY_TYPE PLUMBING
J 0
(-3425 5900);
DISPLAY 0.872340 (-3425 5900);
PAINT GREEN (-3425 5900);
DISPLAY INVISIBLE (-3425 5900);
FORCEPROP 1 LAST HDL_TAP TRUE
J 0
(-3100 5725);
DISPLAY 0.872340 (-3100 5725);
DISPLAY INVISIBLE (-3100 5725);
FORCEPROP 1 LAST PATH I174
J 0
(-3427 5850);
DISPLAY 0.872340 (-3427 5850);
PAINT GREEN (-3427 5850);
DISPLAY INVISIBLE (-3427 5850);
FORCEADD TAP..1
(-3425 5800);
FORCEPROP 3 LASTPIN (-3475 5800) SIG_NAME M_G_CPU0_SA_DQ<5>
J 0
(-3465 5810);
DISPLAY 0.659574 (-3465 5810);
PAINT MONO (-3465 5810);
DISPLAY INVISIBLE (-3465 5810);
FORCEPROP 1 LASTPIN (-3475 5800) BN 5
J 0
(-3487 5808);
DISPLAY 0.489362 (-3487 5808);
PAINT GREEN (-3487 5808);
FORCEPROP 2 LAST CDS_LIB mstr_standard
J 0
(-3425 5800);
DISPLAY 0.723404 (-3425 5800);
PAINT MONO (-3425 5800);
DISPLAY INVISIBLE (-3425 5800);
FORCEPROP 1 LAST BODY_TYPE PLUMBING
J 0
(-3425 5850);
DISPLAY 0.872340 (-3425 5850);
PAINT GREEN (-3425 5850);
DISPLAY INVISIBLE (-3425 5850);
FORCEPROP 1 LAST HDL_TAP TRUE
J 0
(-3100 5675);
DISPLAY 0.872340 (-3100 5675);
DISPLAY INVISIBLE (-3100 5675);
FORCEPROP 1 LAST PATH I175
J 0
(-3427 5800);
DISPLAY 0.872340 (-3427 5800);
PAINT GREEN (-3427 5800);
DISPLAY INVISIBLE (-3427 5800);
FORCEADD TAP..1
(-3425 5700);
FORCEPROP 3 LASTPIN (-3475 5700) SIG_NAME M_G_CPU0_SA_DQ<7>
J 0
(-3465 5710);
DISPLAY 0.659574 (-3465 5710);
PAINT MONO (-3465 5710);
DISPLAY INVISIBLE (-3465 5710);
FORCEPROP 1 LASTPIN (-3475 5700) BN 7
J 0
(-3487 5708);
DISPLAY 0.489362 (-3487 5708);
PAINT GREEN (-3487 5708);
FORCEPROP 2 LAST CDS_LIB mstr_standard
J 0
(-3425 5700);
DISPLAY 0.723404 (-3425 5700);
PAINT MONO (-3425 5700);
DISPLAY INVISIBLE (-3425 5700);
FORCEPROP 1 LAST BODY_TYPE PLUMBING
J 0
(-3425 5750);
DISPLAY 0.872340 (-3425 5750);
PAINT GREEN (-3425 5750);
DISPLAY INVISIBLE (-3425 5750);
FORCEPROP 1 LAST HDL_TAP TRUE
J 0
(-3100 5575);
DISPLAY 0.872340 (-3100 5575);
DISPLAY INVISIBLE (-3100 5575);
FORCEPROP 1 LAST PATH I176
J 0
(-3427 5700);
DISPLAY 0.872340 (-3427 5700);
PAINT GREEN (-3427 5700);
DISPLAY INVISIBLE (-3427 5700);
FORCEADD TAP..1
(-3425 5750);
FORCEPROP 3 LASTPIN (-3475 5750) SIG_NAME M_G_CPU0_SA_DQ<6>
J 0
(-3465 5760);
DISPLAY 0.659574 (-3465 5760);
PAINT MONO (-3465 5760);
DISPLAY INVISIBLE (-3465 5760);
FORCEPROP 1 LASTPIN (-3475 5750) BN 6
J 0
(-3487 5758);
DISPLAY 0.489362 (-3487 5758);
PAINT GREEN (-3487 5758);
FORCEPROP 2 LAST CDS_LIB mstr_standard
J 0
(-3425 5750);
DISPLAY 0.723404 (-3425 5750);
PAINT MONO (-3425 5750);
DISPLAY INVISIBLE (-3425 5750);
FORCEPROP 1 LAST BODY_TYPE PLUMBING
J 0
(-3425 5800);
DISPLAY 0.872340 (-3425 5800);
PAINT GREEN (-3425 5800);
DISPLAY INVISIBLE (-3425 5800);
FORCEPROP 1 LAST HDL_TAP TRUE
J 0
(-3100 5625);
DISPLAY 0.872340 (-3100 5625);
DISPLAY INVISIBLE (-3100 5625);
FORCEPROP 1 LAST PATH I177
J 0
(-3427 5750);
DISPLAY 0.872340 (-3427 5750);
PAINT GREEN (-3427 5750);
DISPLAY INVISIBLE (-3427 5750);
FORCEADD TAP..1
(-3425 5600);
FORCEPROP 3 LASTPIN (-3475 5600) SIG_NAME M_G_CPU0_SA_DQ<8>
J 0
(-3465 5610);
DISPLAY 0.659574 (-3465 5610);
PAINT MONO (-3465 5610);
DISPLAY INVISIBLE (-3465 5610);
FORCEPROP 1 LASTPIN (-3475 5600) BN 8
J 0
(-3487 5608);
DISPLAY 0.489362 (-3487 5608);
PAINT GREEN (-3487 5608);
FORCEPROP 2 LAST CDS_LIB mstr_standard
J 0
(-3425 5600);
DISPLAY 0.723404 (-3425 5600);
PAINT MONO (-3425 5600);
DISPLAY INVISIBLE (-3425 5600);
FORCEPROP 1 LAST BODY_TYPE PLUMBING
J 0
(-3425 5650);
DISPLAY 0.872340 (-3425 5650);
PAINT GREEN (-3425 5650);
DISPLAY INVISIBLE (-3425 5650);
FORCEPROP 1 LAST HDL_TAP TRUE
J 0
(-3100 5475);
DISPLAY 0.872340 (-3100 5475);
DISPLAY INVISIBLE (-3100 5475);
FORCEPROP 1 LAST PATH I178
J 0
(-3427 5600);
DISPLAY 0.872340 (-3427 5600);
PAINT GREEN (-3427 5600);
DISPLAY INVISIBLE (-3427 5600);
FORCEADD TAP..1
(-3425 5550);
FORCEPROP 3 LASTPIN (-3475 5550) SIG_NAME M_G_CPU0_SA_DQ<9>
J 0
(-3465 5560);
DISPLAY 0.659574 (-3465 5560);
PAINT MONO (-3465 5560);
DISPLAY INVISIBLE (-3465 5560);
FORCEPROP 1 LASTPIN (-3475 5550) BN 9
J 0
(-3487 5558);
DISPLAY 0.489362 (-3487 5558);
PAINT GREEN (-3487 5558);
FORCEPROP 2 LAST CDS_LIB mstr_standard
J 0
(-3425 5550);
DISPLAY 0.723404 (-3425 5550);
PAINT MONO (-3425 5550);
DISPLAY INVISIBLE (-3425 5550);
FORCEPROP 1 LAST BODY_TYPE PLUMBING
J 0
(-3425 5600);
DISPLAY 0.872340 (-3425 5600);
PAINT GREEN (-3425 5600);
DISPLAY INVISIBLE (-3425 5600);
FORCEPROP 1 LAST HDL_TAP TRUE
J 0
(-3100 5425);
DISPLAY 0.872340 (-3100 5425);
DISPLAY INVISIBLE (-3100 5425);
FORCEPROP 1 LAST PATH I179
J 0
(-3427 5550);
DISPLAY 0.872340 (-3427 5550);
PAINT GREEN (-3427 5550);
DISPLAY INVISIBLE (-3427 5550);
FORCEADD TAP..1
(-3425 5450);
FORCEPROP 3 LASTPIN (-3475 5450) SIG_NAME M_G_CPU0_SA_DQ<11>
J 0
(-3465 5460);
DISPLAY 0.659574 (-3465 5460);
PAINT MONO (-3465 5460);
DISPLAY INVISIBLE (-3465 5460);
FORCEPROP 1 LASTPIN (-3475 5450) BN 11
J 0
(-3487 5458);
DISPLAY 0.489362 (-3487 5458);
PAINT GREEN (-3487 5458);
FORCEPROP 2 LAST CDS_LIB mstr_standard
J 0
(-3425 5450);
DISPLAY 0.723404 (-3425 5450);
PAINT MONO (-3425 5450);
DISPLAY INVISIBLE (-3425 5450);
FORCEPROP 1 LAST BODY_TYPE PLUMBING
J 0
(-3425 5500);
DISPLAY 0.872340 (-3425 5500);
PAINT GREEN (-3425 5500);
DISPLAY INVISIBLE (-3425 5500);
FORCEPROP 1 LAST HDL_TAP TRUE
J 0
(-3100 5325);
DISPLAY 0.872340 (-3100 5325);
DISPLAY INVISIBLE (-3100 5325);
FORCEPROP 1 LAST PATH I180
J 0
(-3427 5450);
DISPLAY 0.872340 (-3427 5450);
PAINT GREEN (-3427 5450);
DISPLAY INVISIBLE (-3427 5450);
FORCEADD TAP..1
(-3425 5500);
FORCEPROP 3 LASTPIN (-3475 5500) SIG_NAME M_G_CPU0_SA_DQ<10>
J 0
(-3465 5510);
DISPLAY 0.659574 (-3465 5510);
PAINT MONO (-3465 5510);
DISPLAY INVISIBLE (-3465 5510);
FORCEPROP 1 LASTPIN (-3475 5500) BN 10
J 0
(-3487 5508);
DISPLAY 0.489362 (-3487 5508);
PAINT GREEN (-3487 5508);
FORCEPROP 2 LAST CDS_LIB mstr_standard
J 0
(-3425 5500);
DISPLAY 0.723404 (-3425 5500);
PAINT MONO (-3425 5500);
DISPLAY INVISIBLE (-3425 5500);
FORCEPROP 1 LAST BODY_TYPE PLUMBING
J 0
(-3425 5550);
DISPLAY 0.872340 (-3425 5550);
PAINT GREEN (-3425 5550);
DISPLAY INVISIBLE (-3425 5550);
FORCEPROP 1 LAST HDL_TAP TRUE
J 0
(-3100 5375);
DISPLAY 0.872340 (-3100 5375);
DISPLAY INVISIBLE (-3100 5375);
FORCEPROP 1 LAST PATH I181
J 0
(-3427 5500);
DISPLAY 0.872340 (-3427 5500);
PAINT GREEN (-3427 5500);
DISPLAY INVISIBLE (-3427 5500);
FORCEADD TAP..1
(-3425 5400);
FORCEPROP 3 LASTPIN (-3475 5400) SIG_NAME M_G_CPU0_SA_DQ<12>
J 0
(-3465 5410);
DISPLAY 0.659574 (-3465 5410);
PAINT MONO (-3465 5410);
DISPLAY INVISIBLE (-3465 5410);
FORCEPROP 1 LASTPIN (-3475 5400) BN 12
J 0
(-3487 5408);
DISPLAY 0.489362 (-3487 5408);
PAINT GREEN (-3487 5408);
FORCEPROP 2 LAST CDS_LIB mstr_standard
J 0
(-3425 5400);
DISPLAY 0.723404 (-3425 5400);
PAINT MONO (-3425 5400);
DISPLAY INVISIBLE (-3425 5400);
FORCEPROP 1 LAST BODY_TYPE PLUMBING
J 0
(-3425 5450);
DISPLAY 0.872340 (-3425 5450);
PAINT GREEN (-3425 5450);
DISPLAY INVISIBLE (-3425 5450);
FORCEPROP 1 LAST HDL_TAP TRUE
J 0
(-3100 5275);
DISPLAY 0.872340 (-3100 5275);
DISPLAY INVISIBLE (-3100 5275);
FORCEPROP 1 LAST PATH I182
J 0
(-3427 5400);
DISPLAY 0.872340 (-3427 5400);
PAINT GREEN (-3427 5400);
DISPLAY INVISIBLE (-3427 5400);
FORCEADD TAP..1
(-3425 5350);
FORCEPROP 3 LASTPIN (-3475 5350) SIG_NAME M_G_CPU0_SA_DQ<13>
J 0
(-3465 5360);
DISPLAY 0.659574 (-3465 5360);
PAINT MONO (-3465 5360);
DISPLAY INVISIBLE (-3465 5360);
FORCEPROP 1 LASTPIN (-3475 5350) BN 13
J 0
(-3487 5358);
DISPLAY 0.489362 (-3487 5358);
PAINT GREEN (-3487 5358);
FORCEPROP 2 LAST CDS_LIB mstr_standard
J 0
(-3425 5350);
DISPLAY 0.723404 (-3425 5350);
PAINT MONO (-3425 5350);
DISPLAY INVISIBLE (-3425 5350);
FORCEPROP 1 LAST BODY_TYPE PLUMBING
J 0
(-3425 5400);
DISPLAY 0.872340 (-3425 5400);
PAINT GREEN (-3425 5400);
DISPLAY INVISIBLE (-3425 5400);
FORCEPROP 1 LAST HDL_TAP TRUE
J 0
(-3100 5225);
DISPLAY 0.872340 (-3100 5225);
DISPLAY INVISIBLE (-3100 5225);
FORCEPROP 1 LAST PATH I183
J 0
(-3427 5350);
DISPLAY 0.872340 (-3427 5350);
PAINT GREEN (-3427 5350);
DISPLAY INVISIBLE (-3427 5350);
FORCEADD TAP..1
(-3425 5250);
FORCEPROP 3 LASTPIN (-3475 5250) SIG_NAME M_G_CPU0_SA_DQ<15>
J 0
(-3465 5260);
DISPLAY 0.659574 (-3465 5260);
PAINT MONO (-3465 5260);
DISPLAY INVISIBLE (-3465 5260);
FORCEPROP 1 LASTPIN (-3475 5250) BN 15
J 0
(-3487 5258);
DISPLAY 0.489362 (-3487 5258);
PAINT GREEN (-3487 5258);
FORCEPROP 2 LAST CDS_LIB mstr_standard
J 0
(-3425 5250);
DISPLAY 0.723404 (-3425 5250);
PAINT MONO (-3425 5250);
DISPLAY INVISIBLE (-3425 5250);
FORCEPROP 1 LAST BODY_TYPE PLUMBING
J 0
(-3425 5300);
DISPLAY 0.872340 (-3425 5300);
PAINT GREEN (-3425 5300);
DISPLAY INVISIBLE (-3425 5300);
FORCEPROP 1 LAST HDL_TAP TRUE
J 0
(-3100 5125);
DISPLAY 0.872340 (-3100 5125);
DISPLAY INVISIBLE (-3100 5125);
FORCEPROP 1 LAST PATH I184
J 0
(-3427 5250);
DISPLAY 0.872340 (-3427 5250);
PAINT GREEN (-3427 5250);
DISPLAY INVISIBLE (-3427 5250);
FORCEADD TAP..1
(-3425 5300);
FORCEPROP 3 LASTPIN (-3475 5300) SIG_NAME M_G_CPU0_SA_DQ<14>
J 0
(-3465 5310);
DISPLAY 0.659574 (-3465 5310);
PAINT MONO (-3465 5310);
DISPLAY INVISIBLE (-3465 5310);
FORCEPROP 1 LASTPIN (-3475 5300) BN 14
J 0
(-3487 5308);
DISPLAY 0.489362 (-3487 5308);
PAINT GREEN (-3487 5308);
FORCEPROP 2 LAST CDS_LIB mstr_standard
J 0
(-3425 5300);
DISPLAY 0.723404 (-3425 5300);
PAINT MONO (-3425 5300);
DISPLAY INVISIBLE (-3425 5300);
FORCEPROP 1 LAST BODY_TYPE PLUMBING
J 0
(-3425 5350);
DISPLAY 0.872340 (-3425 5350);
PAINT GREEN (-3425 5350);
DISPLAY INVISIBLE (-3425 5350);
FORCEPROP 1 LAST HDL_TAP TRUE
J 0
(-3100 5175);
DISPLAY 0.872340 (-3100 5175);
DISPLAY INVISIBLE (-3100 5175);
FORCEPROP 1 LAST PATH I185
J 0
(-3427 5300);
DISPLAY 0.872340 (-3427 5300);
PAINT GREEN (-3427 5300);
DISPLAY INVISIBLE (-3427 5300);
FORCEADD TAP..1
(-3425 5150);
FORCEPROP 3 LASTPIN (-3475 5150) SIG_NAME M_G_CPU0_SA_DQ<16>
J 0
(-3465 5160);
DISPLAY 0.659574 (-3465 5160);
PAINT MONO (-3465 5160);
DISPLAY INVISIBLE (-3465 5160);
FORCEPROP 1 LASTPIN (-3475 5150) BN 16
J 0
(-3487 5158);
DISPLAY 0.489362 (-3487 5158);
PAINT GREEN (-3487 5158);
FORCEPROP 2 LAST CDS_LIB mstr_standard
J 0
(-3425 5150);
DISPLAY 0.723404 (-3425 5150);
PAINT MONO (-3425 5150);
DISPLAY INVISIBLE (-3425 5150);
FORCEPROP 1 LAST BODY_TYPE PLUMBING
J 0
(-3425 5200);
DISPLAY 0.872340 (-3425 5200);
PAINT GREEN (-3425 5200);
DISPLAY INVISIBLE (-3425 5200);
FORCEPROP 1 LAST HDL_TAP TRUE
J 0
(-3100 5025);
DISPLAY 0.872340 (-3100 5025);
DISPLAY INVISIBLE (-3100 5025);
FORCEPROP 1 LAST PATH I186
J 0
(-3427 5150);
DISPLAY 0.872340 (-3427 5150);
PAINT GREEN (-3427 5150);
DISPLAY INVISIBLE (-3427 5150);
FORCEADD TAP..1
(-3425 5100);
FORCEPROP 3 LASTPIN (-3475 5100) SIG_NAME M_G_CPU0_SA_DQ<17>
J 0
(-3465 5110);
DISPLAY 0.659574 (-3465 5110);
PAINT MONO (-3465 5110);
DISPLAY INVISIBLE (-3465 5110);
FORCEPROP 1 LASTPIN (-3475 5100) BN 17
J 0
(-3487 5108);
DISPLAY 0.489362 (-3487 5108);
PAINT GREEN (-3487 5108);
FORCEPROP 2 LAST CDS_LIB mstr_standard
J 0
(-3425 5100);
DISPLAY 0.723404 (-3425 5100);
PAINT MONO (-3425 5100);
DISPLAY INVISIBLE (-3425 5100);
FORCEPROP 1 LAST BODY_TYPE PLUMBING
J 0
(-3425 5150);
DISPLAY 0.872340 (-3425 5150);
PAINT GREEN (-3425 5150);
DISPLAY INVISIBLE (-3425 5150);
FORCEPROP 1 LAST HDL_TAP TRUE
J 0
(-3100 4975);
DISPLAY 0.872340 (-3100 4975);
DISPLAY INVISIBLE (-3100 4975);
FORCEPROP 1 LAST PATH I187
J 0
(-3427 5100);
DISPLAY 0.872340 (-3427 5100);
PAINT GREEN (-3427 5100);
DISPLAY INVISIBLE (-3427 5100);
FORCEADD TAP..1
(-3425 5050);
FORCEPROP 3 LASTPIN (-3475 5050) SIG_NAME M_G_CPU0_SA_DQ<18>
J 0
(-3465 5060);
DISPLAY 0.659574 (-3465 5060);
PAINT MONO (-3465 5060);
DISPLAY INVISIBLE (-3465 5060);
FORCEPROP 1 LASTPIN (-3475 5050) BN 18
J 0
(-3487 5058);
DISPLAY 0.489362 (-3487 5058);
PAINT GREEN (-3487 5058);
FORCEPROP 2 LAST CDS_LIB mstr_standard
J 0
(-3425 5050);
DISPLAY 0.723404 (-3425 5050);
PAINT MONO (-3425 5050);
DISPLAY INVISIBLE (-3425 5050);
FORCEPROP 1 LAST BODY_TYPE PLUMBING
J 0
(-3425 5100);
DISPLAY 0.872340 (-3425 5100);
PAINT GREEN (-3425 5100);
DISPLAY INVISIBLE (-3425 5100);
FORCEPROP 1 LAST HDL_TAP TRUE
J 0
(-3100 4925);
DISPLAY 0.872340 (-3100 4925);
DISPLAY INVISIBLE (-3100 4925);
FORCEPROP 1 LAST PATH I188
J 0
(-3427 5050);
DISPLAY 0.872340 (-3427 5050);
PAINT GREEN (-3427 5050);
DISPLAY INVISIBLE (-3427 5050);
FORCEADD TAP..1
(-3425 5000);
FORCEPROP 3 LASTPIN (-3475 5000) SIG_NAME M_G_CPU0_SA_DQ<19>
J 0
(-3465 5010);
DISPLAY 0.659574 (-3465 5010);
PAINT MONO (-3465 5010);
DISPLAY INVISIBLE (-3465 5010);
FORCEPROP 1 LASTPIN (-3475 5000) BN 19
J 0
(-3487 5008);
DISPLAY 0.489362 (-3487 5008);
PAINT GREEN (-3487 5008);
FORCEPROP 2 LAST CDS_LIB mstr_standard
J 0
(-3425 5000);
DISPLAY 0.723404 (-3425 5000);
PAINT MONO (-3425 5000);
DISPLAY INVISIBLE (-3425 5000);
FORCEPROP 1 LAST BODY_TYPE PLUMBING
J 0
(-3425 5050);
DISPLAY 0.872340 (-3425 5050);
PAINT GREEN (-3425 5050);
DISPLAY INVISIBLE (-3425 5050);
FORCEPROP 1 LAST HDL_TAP TRUE
J 0
(-3100 4875);
DISPLAY 0.872340 (-3100 4875);
DISPLAY INVISIBLE (-3100 4875);
FORCEPROP 1 LAST PATH I189
J 0
(-3427 5000);
DISPLAY 0.872340 (-3427 5000);
PAINT GREEN (-3427 5000);
DISPLAY INVISIBLE (-3427 5000);
FORCEADD TAP..1
(-3425 4950);
FORCEPROP 3 LASTPIN (-3475 4950) SIG_NAME M_G_CPU0_SA_DQ<20>
J 0
(-3465 4960);
DISPLAY 0.659574 (-3465 4960);
PAINT MONO (-3465 4960);
DISPLAY INVISIBLE (-3465 4960);
FORCEPROP 1 LASTPIN (-3475 4950) BN 20
J 0
(-3487 4958);
DISPLAY 0.489362 (-3487 4958);
PAINT GREEN (-3487 4958);
FORCEPROP 2 LAST CDS_LIB mstr_standard
J 0
(-3425 4950);
DISPLAY 0.723404 (-3425 4950);
PAINT MONO (-3425 4950);
DISPLAY INVISIBLE (-3425 4950);
FORCEPROP 1 LAST BODY_TYPE PLUMBING
J 0
(-3425 5000);
DISPLAY 0.872340 (-3425 5000);
PAINT GREEN (-3425 5000);
DISPLAY INVISIBLE (-3425 5000);
FORCEPROP 1 LAST HDL_TAP TRUE
J 0
(-3100 4825);
DISPLAY 0.872340 (-3100 4825);
DISPLAY INVISIBLE (-3100 4825);
FORCEPROP 1 LAST PATH I190
J 0
(-3427 4950);
DISPLAY 0.872340 (-3427 4950);
PAINT GREEN (-3427 4950);
DISPLAY INVISIBLE (-3427 4950);
FORCEADD TAP..1
(-3425 4900);
FORCEPROP 3 LASTPIN (-3475 4900) SIG_NAME M_G_CPU0_SA_DQ<21>
J 0
(-3465 4910);
DISPLAY 0.659574 (-3465 4910);
PAINT MONO (-3465 4910);
DISPLAY INVISIBLE (-3465 4910);
FORCEPROP 1 LASTPIN (-3475 4900) BN 21
J 0
(-3487 4908);
DISPLAY 0.489362 (-3487 4908);
PAINT GREEN (-3487 4908);
FORCEPROP 2 LAST CDS_LIB mstr_standard
J 0
(-3425 4900);
DISPLAY 0.723404 (-3425 4900);
PAINT MONO (-3425 4900);
DISPLAY INVISIBLE (-3425 4900);
FORCEPROP 1 LAST BODY_TYPE PLUMBING
J 0
(-3425 4950);
DISPLAY 0.872340 (-3425 4950);
PAINT GREEN (-3425 4950);
DISPLAY INVISIBLE (-3425 4950);
FORCEPROP 1 LAST HDL_TAP TRUE
J 0
(-3100 4775);
DISPLAY 0.872340 (-3100 4775);
DISPLAY INVISIBLE (-3100 4775);
FORCEPROP 1 LAST PATH I191
J 0
(-3427 4900);
DISPLAY 0.872340 (-3427 4900);
PAINT GREEN (-3427 4900);
DISPLAY INVISIBLE (-3427 4900);
FORCEADD TAP..1
(-3425 4800);
FORCEPROP 3 LASTPIN (-3475 4800) SIG_NAME M_G_CPU0_SA_DQ<23>
J 0
(-3465 4810);
DISPLAY 0.659574 (-3465 4810);
PAINT MONO (-3465 4810);
DISPLAY INVISIBLE (-3465 4810);
FORCEPROP 1 LASTPIN (-3475 4800) BN 23
J 0
(-3487 4808);
DISPLAY 0.489362 (-3487 4808);
PAINT GREEN (-3487 4808);
FORCEPROP 2 LAST CDS_LIB mstr_standard
J 0
(-3425 4800);
DISPLAY 0.723404 (-3425 4800);
PAINT MONO (-3425 4800);
DISPLAY INVISIBLE (-3425 4800);
FORCEPROP 1 LAST BODY_TYPE PLUMBING
J 0
(-3425 4850);
DISPLAY 0.872340 (-3425 4850);
PAINT GREEN (-3425 4850);
DISPLAY INVISIBLE (-3425 4850);
FORCEPROP 1 LAST HDL_TAP TRUE
J 0
(-3100 4675);
DISPLAY 0.872340 (-3100 4675);
DISPLAY INVISIBLE (-3100 4675);
FORCEPROP 1 LAST PATH I192
J 0
(-3427 4800);
DISPLAY 0.872340 (-3427 4800);
PAINT GREEN (-3427 4800);
DISPLAY INVISIBLE (-3427 4800);
FORCEADD TAP..1
(-3425 4850);
FORCEPROP 3 LASTPIN (-3475 4850) SIG_NAME M_G_CPU0_SA_DQ<22>
J 0
(-3465 4860);
DISPLAY 0.659574 (-3465 4860);
PAINT MONO (-3465 4860);
DISPLAY INVISIBLE (-3465 4860);
FORCEPROP 1 LASTPIN (-3475 4850) BN 22
J 0
(-3487 4858);
DISPLAY 0.489362 (-3487 4858);
PAINT GREEN (-3487 4858);
FORCEPROP 2 LAST CDS_LIB mstr_standard
J 0
(-3425 4850);
DISPLAY 0.723404 (-3425 4850);
PAINT MONO (-3425 4850);
DISPLAY INVISIBLE (-3425 4850);
FORCEPROP 1 LAST BODY_TYPE PLUMBING
J 0
(-3425 4900);
DISPLAY 0.872340 (-3425 4900);
PAINT GREEN (-3425 4900);
DISPLAY INVISIBLE (-3425 4900);
FORCEPROP 1 LAST HDL_TAP TRUE
J 0
(-3100 4725);
DISPLAY 0.872340 (-3100 4725);
DISPLAY INVISIBLE (-3100 4725);
FORCEPROP 1 LAST PATH I193
J 0
(-3427 4850);
DISPLAY 0.872340 (-3427 4850);
PAINT GREEN (-3427 4850);
DISPLAY INVISIBLE (-3427 4850);
FORCEADD TAP..1
(-3425 4700);
FORCEPROP 3 LASTPIN (-3475 4700) SIG_NAME M_G_CPU0_SA_DQ<24>
J 0
(-3465 4710);
DISPLAY 0.659574 (-3465 4710);
PAINT MONO (-3465 4710);
DISPLAY INVISIBLE (-3465 4710);
FORCEPROP 1 LASTPIN (-3475 4700) BN 24
J 0
(-3487 4708);
DISPLAY 0.489362 (-3487 4708);
PAINT GREEN (-3487 4708);
FORCEPROP 2 LAST CDS_LIB mstr_standard
J 0
(-3425 4700);
DISPLAY 0.723404 (-3425 4700);
PAINT MONO (-3425 4700);
DISPLAY INVISIBLE (-3425 4700);
FORCEPROP 1 LAST BODY_TYPE PLUMBING
J 0
(-3425 4750);
DISPLAY 0.872340 (-3425 4750);
PAINT GREEN (-3425 4750);
DISPLAY INVISIBLE (-3425 4750);
FORCEPROP 1 LAST HDL_TAP TRUE
J 0
(-3100 4575);
DISPLAY 0.872340 (-3100 4575);
DISPLAY INVISIBLE (-3100 4575);
FORCEPROP 1 LAST PATH I194
J 0
(-3427 4700);
DISPLAY 0.872340 (-3427 4700);
PAINT GREEN (-3427 4700);
DISPLAY INVISIBLE (-3427 4700);
FORCEADD TAP..1
(-3425 4650);
FORCEPROP 3 LASTPIN (-3475 4650) SIG_NAME M_G_CPU0_SA_DQ<25>
J 0
(-3465 4660);
DISPLAY 0.659574 (-3465 4660);
PAINT MONO (-3465 4660);
DISPLAY INVISIBLE (-3465 4660);
FORCEPROP 1 LASTPIN (-3475 4650) BN 25
J 0
(-3487 4658);
DISPLAY 0.489362 (-3487 4658);
PAINT GREEN (-3487 4658);
FORCEPROP 2 LAST CDS_LIB mstr_standard
J 0
(-3425 4650);
DISPLAY 0.723404 (-3425 4650);
PAINT MONO (-3425 4650);
DISPLAY INVISIBLE (-3425 4650);
FORCEPROP 1 LAST BODY_TYPE PLUMBING
J 0
(-3425 4700);
DISPLAY 0.872340 (-3425 4700);
PAINT GREEN (-3425 4700);
DISPLAY INVISIBLE (-3425 4700);
FORCEPROP 1 LAST HDL_TAP TRUE
J 0
(-3100 4525);
DISPLAY 0.872340 (-3100 4525);
DISPLAY INVISIBLE (-3100 4525);
FORCEPROP 1 LAST PATH I195
J 0
(-3427 4650);
DISPLAY 0.872340 (-3427 4650);
PAINT GREEN (-3427 4650);
DISPLAY INVISIBLE (-3427 4650);
FORCEADD TAP..1
(-3425 4550);
FORCEPROP 3 LASTPIN (-3475 4550) SIG_NAME M_G_CPU0_SA_DQ<27>
J 0
(-3465 4560);
DISPLAY 0.659574 (-3465 4560);
PAINT MONO (-3465 4560);
DISPLAY INVISIBLE (-3465 4560);
FORCEPROP 1 LASTPIN (-3475 4550) BN 27
J 0
(-3487 4558);
DISPLAY 0.489362 (-3487 4558);
PAINT GREEN (-3487 4558);
FORCEPROP 2 LAST CDS_LIB mstr_standard
J 0
(-3425 4550);
DISPLAY 0.723404 (-3425 4550);
PAINT MONO (-3425 4550);
DISPLAY INVISIBLE (-3425 4550);
FORCEPROP 1 LAST BODY_TYPE PLUMBING
J 0
(-3425 4600);
DISPLAY 0.872340 (-3425 4600);
PAINT GREEN (-3425 4600);
DISPLAY INVISIBLE (-3425 4600);
FORCEPROP 1 LAST HDL_TAP TRUE
J 0
(-3100 4425);
DISPLAY 0.872340 (-3100 4425);
DISPLAY INVISIBLE (-3100 4425);
FORCEPROP 1 LAST PATH I196
J 0
(-3427 4550);
DISPLAY 0.872340 (-3427 4550);
PAINT GREEN (-3427 4550);
DISPLAY INVISIBLE (-3427 4550);
FORCEADD TAP..1
(-3425 4600);
FORCEPROP 3 LASTPIN (-3475 4600) SIG_NAME M_G_CPU0_SA_DQ<26>
J 0
(-3465 4610);
DISPLAY 0.659574 (-3465 4610);
PAINT MONO (-3465 4610);
DISPLAY INVISIBLE (-3465 4610);
FORCEPROP 1 LASTPIN (-3475 4600) BN 26
J 0
(-3487 4608);
DISPLAY 0.489362 (-3487 4608);
PAINT GREEN (-3487 4608);
FORCEPROP 2 LAST CDS_LIB mstr_standard
J 0
(-3425 4600);
DISPLAY 0.723404 (-3425 4600);
PAINT MONO (-3425 4600);
DISPLAY INVISIBLE (-3425 4600);
FORCEPROP 1 LAST BODY_TYPE PLUMBING
J 0
(-3425 4650);
DISPLAY 0.872340 (-3425 4650);
PAINT GREEN (-3425 4650);
DISPLAY INVISIBLE (-3425 4650);
FORCEPROP 1 LAST HDL_TAP TRUE
J 0
(-3100 4475);
DISPLAY 0.872340 (-3100 4475);
DISPLAY INVISIBLE (-3100 4475);
FORCEPROP 1 LAST PATH I197
J 0
(-3427 4600);
DISPLAY 0.872340 (-3427 4600);
PAINT GREEN (-3427 4600);
DISPLAY INVISIBLE (-3427 4600);
FORCEADD TAP..1
(-3425 4500);
FORCEPROP 3 LASTPIN (-3475 4500) SIG_NAME M_G_CPU0_SA_DQ<28>
J 0
(-3465 4510);
DISPLAY 0.659574 (-3465 4510);
PAINT MONO (-3465 4510);
DISPLAY INVISIBLE (-3465 4510);
FORCEPROP 1 LASTPIN (-3475 4500) BN 28
J 0
(-3487 4508);
DISPLAY 0.489362 (-3487 4508);
PAINT GREEN (-3487 4508);
FORCEPROP 2 LAST CDS_LIB mstr_standard
J 0
(-3425 4500);
DISPLAY 0.723404 (-3425 4500);
PAINT MONO (-3425 4500);
DISPLAY INVISIBLE (-3425 4500);
FORCEPROP 1 LAST BODY_TYPE PLUMBING
J 0
(-3425 4550);
DISPLAY 0.872340 (-3425 4550);
PAINT GREEN (-3425 4550);
DISPLAY INVISIBLE (-3425 4550);
FORCEPROP 1 LAST HDL_TAP TRUE
J 0
(-3100 4375);
DISPLAY 0.872340 (-3100 4375);
DISPLAY INVISIBLE (-3100 4375);
FORCEPROP 1 LAST PATH I198
J 0
(-3427 4500);
DISPLAY 0.872340 (-3427 4500);
PAINT GREEN (-3427 4500);
DISPLAY INVISIBLE (-3427 4500);
FORCEADD TAP..1
(-3425 4450);
FORCEPROP 3 LASTPIN (-3475 4450) SIG_NAME M_G_CPU0_SA_DQ<29>
J 0
(-3465 4460);
DISPLAY 0.659574 (-3465 4460);
PAINT MONO (-3465 4460);
DISPLAY INVISIBLE (-3465 4460);
FORCEPROP 1 LASTPIN (-3475 4450) BN 29
J 0
(-3487 4458);
DISPLAY 0.489362 (-3487 4458);
PAINT GREEN (-3487 4458);
FORCEPROP 2 LAST CDS_LIB mstr_standard
J 0
(-3425 4450);
DISPLAY 0.723404 (-3425 4450);
PAINT MONO (-3425 4450);
DISPLAY INVISIBLE (-3425 4450);
FORCEPROP 1 LAST BODY_TYPE PLUMBING
J 0
(-3425 4500);
DISPLAY 0.872340 (-3425 4500);
PAINT GREEN (-3425 4500);
DISPLAY INVISIBLE (-3425 4500);
FORCEPROP 1 LAST HDL_TAP TRUE
J 0
(-3100 4325);
DISPLAY 0.872340 (-3100 4325);
DISPLAY INVISIBLE (-3100 4325);
FORCEPROP 1 LAST PATH I199
J 0
(-3427 4450);
DISPLAY 0.872340 (-3427 4450);
PAINT GREEN (-3427 4450);
DISPLAY INVISIBLE (-3427 4450);
FORCEADD TAP..1
(-3425 4400);
FORCEPROP 3 LASTPIN (-3475 4400) SIG_NAME M_G_CPU0_SA_DQ<30>
J 0
(-3465 4410);
DISPLAY 0.659574 (-3465 4410);
PAINT MONO (-3465 4410);
DISPLAY INVISIBLE (-3465 4410);
FORCEPROP 1 LASTPIN (-3475 4400) BN 30
J 0
(-3487 4408);
DISPLAY 0.489362 (-3487 4408);
PAINT GREEN (-3487 4408);
FORCEPROP 2 LAST CDS_LIB mstr_standard
J 0
(-3425 4400);
DISPLAY 0.723404 (-3425 4400);
PAINT MONO (-3425 4400);
DISPLAY INVISIBLE (-3425 4400);
FORCEPROP 1 LAST BODY_TYPE PLUMBING
J 0
(-3425 4450);
DISPLAY 0.872340 (-3425 4450);
PAINT GREEN (-3425 4450);
DISPLAY INVISIBLE (-3425 4450);
FORCEPROP 1 LAST HDL_TAP TRUE
J 0
(-3100 4275);
DISPLAY 0.872340 (-3100 4275);
DISPLAY INVISIBLE (-3100 4275);
FORCEPROP 1 LAST PATH I200
J 0
(-3427 4400);
DISPLAY 0.872340 (-3427 4400);
PAINT GREEN (-3427 4400);
DISPLAY INVISIBLE (-3427 4400);
FORCEADD TAP..1
(-3425 4250);
FORCEPROP 3 LASTPIN (-3475 4250) SIG_NAME M_G_CPU0_SB_DQ<0>
J 0
(-3465 4260);
DISPLAY 0.659574 (-3465 4260);
PAINT MONO (-3465 4260);
DISPLAY INVISIBLE (-3465 4260);
FORCEPROP 1 LASTPIN (-3475 4250) BN 0
J 0
(-3487 4258);
DISPLAY 0.489362 (-3487 4258);
PAINT GREEN (-3487 4258);
FORCEPROP 2 LAST CDS_LIB mstr_standard
J 0
(-3425 4250);
DISPLAY 0.723404 (-3425 4250);
PAINT MONO (-3425 4250);
DISPLAY INVISIBLE (-3425 4250);
FORCEPROP 1 LAST BODY_TYPE PLUMBING
J 0
(-3425 4300);
DISPLAY 0.872340 (-3425 4300);
PAINT GREEN (-3425 4300);
DISPLAY INVISIBLE (-3425 4300);
FORCEPROP 1 LAST HDL_TAP TRUE
J 0
(-3100 4125);
DISPLAY 0.872340 (-3100 4125);
DISPLAY INVISIBLE (-3100 4125);
FORCEPROP 1 LAST PATH I201
J 0
(-3427 4250);
DISPLAY 0.872340 (-3427 4250);
PAINT GREEN (-3427 4250);
DISPLAY INVISIBLE (-3427 4250);
FORCEADD TAP..1
(-3425 4350);
FORCEPROP 3 LASTPIN (-3475 4350) SIG_NAME M_G_CPU0_SA_DQ<31>
J 0
(-3465 4360);
DISPLAY 0.659574 (-3465 4360);
PAINT MONO (-3465 4360);
DISPLAY INVISIBLE (-3465 4360);
FORCEPROP 1 LASTPIN (-3475 4350) BN 31
J 0
(-3487 4358);
DISPLAY 0.489362 (-3487 4358);
PAINT GREEN (-3487 4358);
FORCEPROP 2 LAST CDS_LIB mstr_standard
J 0
(-3425 4350);
DISPLAY 0.723404 (-3425 4350);
PAINT MONO (-3425 4350);
DISPLAY INVISIBLE (-3425 4350);
FORCEPROP 1 LAST BODY_TYPE PLUMBING
J 0
(-3425 4400);
DISPLAY 0.872340 (-3425 4400);
PAINT GREEN (-3425 4400);
DISPLAY INVISIBLE (-3425 4400);
FORCEPROP 1 LAST HDL_TAP TRUE
J 0
(-3100 4225);
DISPLAY 0.872340 (-3100 4225);
DISPLAY INVISIBLE (-3100 4225);
FORCEPROP 1 LAST PATH I202
J 0
(-3427 4350);
DISPLAY 0.872340 (-3427 4350);
PAINT GREEN (-3427 4350);
DISPLAY INVISIBLE (-3427 4350);
FORCEADD TAP..1
(-3425 4200);
FORCEPROP 3 LASTPIN (-3475 4200) SIG_NAME M_G_CPU0_SB_DQ<1>
J 0
(-3465 4210);
DISPLAY 0.659574 (-3465 4210);
PAINT MONO (-3465 4210);
DISPLAY INVISIBLE (-3465 4210);
FORCEPROP 1 LASTPIN (-3475 4200) BN 1
J 0
(-3487 4208);
DISPLAY 0.489362 (-3487 4208);
PAINT GREEN (-3487 4208);
FORCEPROP 2 LAST CDS_LIB mstr_standard
J 0
(-3425 4200);
DISPLAY 0.723404 (-3425 4200);
PAINT MONO (-3425 4200);
DISPLAY INVISIBLE (-3425 4200);
FORCEPROP 1 LAST BODY_TYPE PLUMBING
J 0
(-3425 4250);
DISPLAY 0.872340 (-3425 4250);
PAINT GREEN (-3425 4250);
DISPLAY INVISIBLE (-3425 4250);
FORCEPROP 1 LAST HDL_TAP TRUE
J 0
(-3100 4075);
DISPLAY 0.872340 (-3100 4075);
DISPLAY INVISIBLE (-3100 4075);
FORCEPROP 1 LAST PATH I203
J 0
(-3427 4200);
DISPLAY 0.872340 (-3427 4200);
PAINT GREEN (-3427 4200);
DISPLAY INVISIBLE (-3427 4200);
FORCEADD TAP..1
(-3425 4150);
FORCEPROP 3 LASTPIN (-3475 4150) SIG_NAME M_G_CPU0_SB_DQ<2>
J 0
(-3465 4160);
DISPLAY 0.659574 (-3465 4160);
PAINT MONO (-3465 4160);
DISPLAY INVISIBLE (-3465 4160);
FORCEPROP 1 LASTPIN (-3475 4150) BN 2
J 0
(-3487 4158);
DISPLAY 0.489362 (-3487 4158);
PAINT GREEN (-3487 4158);
FORCEPROP 2 LAST CDS_LIB mstr_standard
J 0
(-3425 4150);
DISPLAY 0.723404 (-3425 4150);
PAINT MONO (-3425 4150);
DISPLAY INVISIBLE (-3425 4150);
FORCEPROP 1 LAST BODY_TYPE PLUMBING
J 0
(-3425 4200);
DISPLAY 0.872340 (-3425 4200);
PAINT GREEN (-3425 4200);
DISPLAY INVISIBLE (-3425 4200);
FORCEPROP 1 LAST HDL_TAP TRUE
J 0
(-3100 4025);
DISPLAY 0.872340 (-3100 4025);
DISPLAY INVISIBLE (-3100 4025);
FORCEPROP 1 LAST PATH I204
J 0
(-3427 4150);
DISPLAY 0.872340 (-3427 4150);
PAINT GREEN (-3427 4150);
DISPLAY INVISIBLE (-3427 4150);
FORCEADD TAP..1
(-3425 4100);
FORCEPROP 3 LASTPIN (-3475 4100) SIG_NAME M_G_CPU0_SB_DQ<3>
J 0
(-3465 4110);
DISPLAY 0.659574 (-3465 4110);
PAINT MONO (-3465 4110);
DISPLAY INVISIBLE (-3465 4110);
FORCEPROP 1 LASTPIN (-3475 4100) BN 3
J 0
(-3487 4108);
DISPLAY 0.489362 (-3487 4108);
PAINT GREEN (-3487 4108);
FORCEPROP 2 LAST CDS_LIB mstr_standard
J 0
(-3425 4100);
DISPLAY 0.723404 (-3425 4100);
PAINT MONO (-3425 4100);
DISPLAY INVISIBLE (-3425 4100);
FORCEPROP 1 LAST BODY_TYPE PLUMBING
J 0
(-3425 4150);
DISPLAY 0.872340 (-3425 4150);
PAINT GREEN (-3425 4150);
DISPLAY INVISIBLE (-3425 4150);
FORCEPROP 1 LAST HDL_TAP TRUE
J 0
(-3100 3975);
DISPLAY 0.872340 (-3100 3975);
DISPLAY INVISIBLE (-3100 3975);
FORCEPROP 1 LAST PATH I205
J 0
(-3427 4100);
DISPLAY 0.872340 (-3427 4100);
PAINT GREEN (-3427 4100);
DISPLAY INVISIBLE (-3427 4100);
FORCEADD OFFPAGE..6
R 2
(-2825 2500);
FORCEPROP 2 LAST $XR0 92 
J 0
(-2611 2500);
DISPLAY 0.638298 (-2611 2500);
PAINT MONO (-2611 2500);
FORCEPROP 2 LAST CDS_LIB mstr_standard
J 2
(-2825 2500);
DISPLAY 0.723404 (-2825 2500);
PAINT MONO (-2825 2500);
DISPLAY INVISIBLE (-2825 2500);
FORCEPROP 1 LAST OFFPAGE TRUE
J 2
(-3150 2375);
DISPLAY 0.872340 (-3150 2375);
PAINT GREEN (-3150 2375);
DISPLAY INVISIBLE (-3150 2375);
FORCEPROP 1 LAST COMMENT_BODY TRUE
J 2
(-2925 2425);
DISPLAY 0.872340 (-2925 2425);
PAINT GREEN (-2925 2425);
DISPLAY INVISIBLE (-2925 2425);
FORCEPROP 2 LAST PATH I206
J 0
(-2600 2550);
DISPLAY 1.021277 (-2600 2550);
DISPLAY INVISIBLE (-2600 2550);
FORCEADD TAP..1
(-3425 4050);
FORCEPROP 3 LASTPIN (-3475 4050) SIG_NAME M_G_CPU0_SB_DQ<4>
J 0
(-3465 4060);
DISPLAY 0.659574 (-3465 4060);
PAINT MONO (-3465 4060);
DISPLAY INVISIBLE (-3465 4060);
FORCEPROP 1 LASTPIN (-3475 4050) BN 4
J 0
(-3487 4058);
DISPLAY 0.489362 (-3487 4058);
PAINT GREEN (-3487 4058);
FORCEPROP 2 LAST CDS_LIB mstr_standard
J 0
(-3425 4050);
DISPLAY 0.723404 (-3425 4050);
PAINT MONO (-3425 4050);
DISPLAY INVISIBLE (-3425 4050);
FORCEPROP 1 LAST BODY_TYPE PLUMBING
J 0
(-3425 4100);
DISPLAY 0.872340 (-3425 4100);
PAINT GREEN (-3425 4100);
DISPLAY INVISIBLE (-3425 4100);
FORCEPROP 1 LAST HDL_TAP TRUE
J 0
(-3100 3925);
DISPLAY 0.872340 (-3100 3925);
DISPLAY INVISIBLE (-3100 3925);
FORCEPROP 1 LAST PATH I207
J 0
(-3427 4050);
DISPLAY 0.872340 (-3427 4050);
PAINT GREEN (-3427 4050);
DISPLAY INVISIBLE (-3427 4050);
FORCEADD TAP..1
(-3425 4000);
FORCEPROP 3 LASTPIN (-3475 4000) SIG_NAME M_G_CPU0_SB_DQ<5>
J 0
(-3465 4010);
DISPLAY 0.659574 (-3465 4010);
PAINT MONO (-3465 4010);
DISPLAY INVISIBLE (-3465 4010);
FORCEPROP 1 LASTPIN (-3475 4000) BN 5
J 0
(-3487 4008);
DISPLAY 0.489362 (-3487 4008);
PAINT GREEN (-3487 4008);
FORCEPROP 2 LAST CDS_LIB mstr_standard
J 0
(-3425 4000);
DISPLAY 0.723404 (-3425 4000);
PAINT MONO (-3425 4000);
DISPLAY INVISIBLE (-3425 4000);
FORCEPROP 1 LAST BODY_TYPE PLUMBING
J 0
(-3425 4050);
DISPLAY 0.872340 (-3425 4050);
PAINT GREEN (-3425 4050);
DISPLAY INVISIBLE (-3425 4050);
FORCEPROP 1 LAST HDL_TAP TRUE
J 0
(-3100 3875);
DISPLAY 0.872340 (-3100 3875);
DISPLAY INVISIBLE (-3100 3875);
FORCEPROP 1 LAST PATH I208
J 0
(-3427 4000);
DISPLAY 0.872340 (-3427 4000);
PAINT GREEN (-3427 4000);
DISPLAY INVISIBLE (-3427 4000);
FORCEADD TAP..1
(-3425 3900);
FORCEPROP 3 LASTPIN (-3475 3900) SIG_NAME M_G_CPU0_SB_DQ<7>
J 0
(-3465 3910);
DISPLAY 0.659574 (-3465 3910);
PAINT MONO (-3465 3910);
DISPLAY INVISIBLE (-3465 3910);
FORCEPROP 1 LASTPIN (-3475 3900) BN 7
J 0
(-3487 3908);
DISPLAY 0.489362 (-3487 3908);
PAINT GREEN (-3487 3908);
FORCEPROP 2 LAST CDS_LIB mstr_standard
J 0
(-3425 3900);
DISPLAY 0.723404 (-3425 3900);
PAINT MONO (-3425 3900);
DISPLAY INVISIBLE (-3425 3900);
FORCEPROP 1 LAST BODY_TYPE PLUMBING
J 0
(-3425 3950);
DISPLAY 0.872340 (-3425 3950);
PAINT GREEN (-3425 3950);
DISPLAY INVISIBLE (-3425 3950);
FORCEPROP 1 LAST HDL_TAP TRUE
J 0
(-3100 3775);
DISPLAY 0.872340 (-3100 3775);
DISPLAY INVISIBLE (-3100 3775);
FORCEPROP 1 LAST PATH I209
J 0
(-3427 3900);
DISPLAY 0.872340 (-3427 3900);
PAINT GREEN (-3427 3900);
DISPLAY INVISIBLE (-3427 3900);
FORCEADD TAP..1
(-3425 3950);
FORCEPROP 3 LASTPIN (-3475 3950) SIG_NAME M_G_CPU0_SB_DQ<6>
J 0
(-3465 3960);
DISPLAY 0.659574 (-3465 3960);
PAINT MONO (-3465 3960);
DISPLAY INVISIBLE (-3465 3960);
FORCEPROP 1 LASTPIN (-3475 3950) BN 6
J 0
(-3487 3958);
DISPLAY 0.489362 (-3487 3958);
PAINT GREEN (-3487 3958);
FORCEPROP 2 LAST CDS_LIB mstr_standard
J 0
(-3425 3950);
DISPLAY 0.723404 (-3425 3950);
PAINT MONO (-3425 3950);
DISPLAY INVISIBLE (-3425 3950);
FORCEPROP 1 LAST BODY_TYPE PLUMBING
J 0
(-3425 4000);
DISPLAY 0.872340 (-3425 4000);
PAINT GREEN (-3425 4000);
DISPLAY INVISIBLE (-3425 4000);
FORCEPROP 1 LAST HDL_TAP TRUE
J 0
(-3100 3825);
DISPLAY 0.872340 (-3100 3825);
DISPLAY INVISIBLE (-3100 3825);
FORCEPROP 1 LAST PATH I210
J 0
(-3427 3950);
DISPLAY 0.872340 (-3427 3950);
PAINT GREEN (-3427 3950);
DISPLAY INVISIBLE (-3427 3950);
FORCEADD TAP..1
(-3425 3800);
FORCEPROP 3 LASTPIN (-3475 3800) SIG_NAME M_G_CPU0_SB_DQ<8>
J 0
(-3465 3810);
DISPLAY 0.659574 (-3465 3810);
PAINT MONO (-3465 3810);
DISPLAY INVISIBLE (-3465 3810);
FORCEPROP 1 LASTPIN (-3475 3800) BN 8
J 0
(-3487 3808);
DISPLAY 0.489362 (-3487 3808);
PAINT GREEN (-3487 3808);
FORCEPROP 2 LAST CDS_LIB mstr_standard
J 0
(-3425 3800);
DISPLAY 0.723404 (-3425 3800);
PAINT MONO (-3425 3800);
DISPLAY INVISIBLE (-3425 3800);
FORCEPROP 1 LAST BODY_TYPE PLUMBING
J 0
(-3425 3850);
DISPLAY 0.872340 (-3425 3850);
PAINT GREEN (-3425 3850);
DISPLAY INVISIBLE (-3425 3850);
FORCEPROP 1 LAST HDL_TAP TRUE
J 0
(-3100 3675);
DISPLAY 0.872340 (-3100 3675);
DISPLAY INVISIBLE (-3100 3675);
FORCEPROP 1 LAST PATH I211
J 0
(-3427 3800);
DISPLAY 0.872340 (-3427 3800);
PAINT GREEN (-3427 3800);
DISPLAY INVISIBLE (-3427 3800);
FORCEADD TAP..1
(-3425 3750);
FORCEPROP 3 LASTPIN (-3475 3750) SIG_NAME M_G_CPU0_SB_DQ<9>
J 0
(-3465 3760);
DISPLAY 0.659574 (-3465 3760);
PAINT MONO (-3465 3760);
DISPLAY INVISIBLE (-3465 3760);
FORCEPROP 1 LASTPIN (-3475 3750) BN 9
J 0
(-3487 3758);
DISPLAY 0.489362 (-3487 3758);
PAINT GREEN (-3487 3758);
FORCEPROP 2 LAST CDS_LIB mstr_standard
J 0
(-3425 3750);
DISPLAY 0.723404 (-3425 3750);
PAINT MONO (-3425 3750);
DISPLAY INVISIBLE (-3425 3750);
FORCEPROP 1 LAST BODY_TYPE PLUMBING
J 0
(-3425 3800);
DISPLAY 0.872340 (-3425 3800);
PAINT GREEN (-3425 3800);
DISPLAY INVISIBLE (-3425 3800);
FORCEPROP 1 LAST HDL_TAP TRUE
J 0
(-3100 3625);
DISPLAY 0.872340 (-3100 3625);
DISPLAY INVISIBLE (-3100 3625);
FORCEPROP 1 LAST PATH I212
J 0
(-3427 3750);
DISPLAY 0.872340 (-3427 3750);
PAINT GREEN (-3427 3750);
DISPLAY INVISIBLE (-3427 3750);
FORCEADD TAP..1
(-3425 3650);
FORCEPROP 3 LASTPIN (-3475 3650) SIG_NAME M_G_CPU0_SB_DQ<11>
J 0
(-3465 3660);
DISPLAY 0.659574 (-3465 3660);
PAINT MONO (-3465 3660);
DISPLAY INVISIBLE (-3465 3660);
FORCEPROP 1 LASTPIN (-3475 3650) BN 11
J 0
(-3487 3658);
DISPLAY 0.489362 (-3487 3658);
PAINT GREEN (-3487 3658);
FORCEPROP 2 LAST CDS_LIB mstr_standard
J 0
(-3425 3650);
DISPLAY 0.723404 (-3425 3650);
PAINT MONO (-3425 3650);
DISPLAY INVISIBLE (-3425 3650);
FORCEPROP 1 LAST BODY_TYPE PLUMBING
J 0
(-3425 3700);
DISPLAY 0.872340 (-3425 3700);
PAINT GREEN (-3425 3700);
DISPLAY INVISIBLE (-3425 3700);
FORCEPROP 1 LAST HDL_TAP TRUE
J 0
(-3100 3525);
DISPLAY 0.872340 (-3100 3525);
DISPLAY INVISIBLE (-3100 3525);
FORCEPROP 1 LAST PATH I213
J 0
(-3427 3650);
DISPLAY 0.872340 (-3427 3650);
PAINT GREEN (-3427 3650);
DISPLAY INVISIBLE (-3427 3650);
FORCEADD TAP..1
(-3425 3700);
FORCEPROP 3 LASTPIN (-3475 3700) SIG_NAME M_G_CPU0_SB_DQ<10>
J 0
(-3465 3710);
DISPLAY 0.659574 (-3465 3710);
PAINT MONO (-3465 3710);
DISPLAY INVISIBLE (-3465 3710);
FORCEPROP 1 LASTPIN (-3475 3700) BN 10
J 0
(-3487 3708);
DISPLAY 0.489362 (-3487 3708);
PAINT GREEN (-3487 3708);
FORCEPROP 2 LAST CDS_LIB mstr_standard
J 0
(-3425 3700);
DISPLAY 0.723404 (-3425 3700);
PAINT MONO (-3425 3700);
DISPLAY INVISIBLE (-3425 3700);
FORCEPROP 1 LAST BODY_TYPE PLUMBING
J 0
(-3425 3750);
DISPLAY 0.872340 (-3425 3750);
PAINT GREEN (-3425 3750);
DISPLAY INVISIBLE (-3425 3750);
FORCEPROP 1 LAST HDL_TAP TRUE
J 0
(-3100 3575);
DISPLAY 0.872340 (-3100 3575);
DISPLAY INVISIBLE (-3100 3575);
FORCEPROP 1 LAST PATH I214
J 0
(-3427 3700);
DISPLAY 0.872340 (-3427 3700);
PAINT GREEN (-3427 3700);
DISPLAY INVISIBLE (-3427 3700);
FORCEADD TAP..1
(-3425 3600);
FORCEPROP 3 LASTPIN (-3475 3600) SIG_NAME M_G_CPU0_SB_DQ<12>
J 0
(-3465 3610);
DISPLAY 0.659574 (-3465 3610);
PAINT MONO (-3465 3610);
DISPLAY INVISIBLE (-3465 3610);
FORCEPROP 1 LASTPIN (-3475 3600) BN 12
J 0
(-3487 3608);
DISPLAY 0.489362 (-3487 3608);
PAINT GREEN (-3487 3608);
FORCEPROP 2 LAST CDS_LIB mstr_standard
J 0
(-3425 3600);
DISPLAY 0.723404 (-3425 3600);
PAINT MONO (-3425 3600);
DISPLAY INVISIBLE (-3425 3600);
FORCEPROP 1 LAST BODY_TYPE PLUMBING
J 0
(-3425 3650);
DISPLAY 0.872340 (-3425 3650);
PAINT GREEN (-3425 3650);
DISPLAY INVISIBLE (-3425 3650);
FORCEPROP 1 LAST HDL_TAP TRUE
J 0
(-3100 3475);
DISPLAY 0.872340 (-3100 3475);
DISPLAY INVISIBLE (-3100 3475);
FORCEPROP 1 LAST PATH I215
J 0
(-3427 3600);
DISPLAY 0.872340 (-3427 3600);
PAINT GREEN (-3427 3600);
DISPLAY INVISIBLE (-3427 3600);
FORCEADD TAP..1
(-3425 3550);
FORCEPROP 3 LASTPIN (-3475 3550) SIG_NAME M_G_CPU0_SB_DQ<13>
J 0
(-3465 3560);
DISPLAY 0.659574 (-3465 3560);
PAINT MONO (-3465 3560);
DISPLAY INVISIBLE (-3465 3560);
FORCEPROP 1 LASTPIN (-3475 3550) BN 13
J 0
(-3487 3558);
DISPLAY 0.489362 (-3487 3558);
PAINT GREEN (-3487 3558);
FORCEPROP 2 LAST CDS_LIB mstr_standard
J 0
(-3425 3550);
DISPLAY 0.723404 (-3425 3550);
PAINT MONO (-3425 3550);
DISPLAY INVISIBLE (-3425 3550);
FORCEPROP 1 LAST BODY_TYPE PLUMBING
J 0
(-3425 3600);
DISPLAY 0.872340 (-3425 3600);
PAINT GREEN (-3425 3600);
DISPLAY INVISIBLE (-3425 3600);
FORCEPROP 1 LAST HDL_TAP TRUE
J 0
(-3100 3425);
DISPLAY 0.872340 (-3100 3425);
DISPLAY INVISIBLE (-3100 3425);
FORCEPROP 1 LAST PATH I216
J 0
(-3427 3550);
DISPLAY 0.872340 (-3427 3550);
PAINT GREEN (-3427 3550);
DISPLAY INVISIBLE (-3427 3550);
FORCEADD TAP..1
(-3425 3500);
FORCEPROP 3 LASTPIN (-3475 3500) SIG_NAME M_G_CPU0_SB_DQ<14>
J 0
(-3465 3510);
DISPLAY 0.659574 (-3465 3510);
PAINT MONO (-3465 3510);
DISPLAY INVISIBLE (-3465 3510);
FORCEPROP 1 LASTPIN (-3475 3500) BN 14
J 0
(-3487 3508);
DISPLAY 0.489362 (-3487 3508);
PAINT GREEN (-3487 3508);
FORCEPROP 2 LAST CDS_LIB mstr_standard
J 0
(-3425 3500);
DISPLAY 0.723404 (-3425 3500);
PAINT MONO (-3425 3500);
DISPLAY INVISIBLE (-3425 3500);
FORCEPROP 1 LAST BODY_TYPE PLUMBING
J 0
(-3425 3550);
DISPLAY 0.872340 (-3425 3550);
PAINT GREEN (-3425 3550);
DISPLAY INVISIBLE (-3425 3550);
FORCEPROP 1 LAST HDL_TAP TRUE
J 0
(-3100 3375);
DISPLAY 0.872340 (-3100 3375);
DISPLAY INVISIBLE (-3100 3375);
FORCEPROP 1 LAST PATH I217
J 0
(-3427 3500);
DISPLAY 0.872340 (-3427 3500);
PAINT GREEN (-3427 3500);
DISPLAY INVISIBLE (-3427 3500);
FORCEADD TAP..1
(-3425 3350);
FORCEPROP 3 LASTPIN (-3475 3350) SIG_NAME M_G_CPU0_SB_DQ<16>
J 0
(-3465 3360);
DISPLAY 0.659574 (-3465 3360);
PAINT MONO (-3465 3360);
DISPLAY INVISIBLE (-3465 3360);
FORCEPROP 1 LASTPIN (-3475 3350) BN 16
J 0
(-3487 3358);
DISPLAY 0.489362 (-3487 3358);
PAINT GREEN (-3487 3358);
FORCEPROP 2 LAST CDS_LIB mstr_standard
J 0
(-3425 3350);
DISPLAY 0.723404 (-3425 3350);
PAINT MONO (-3425 3350);
DISPLAY INVISIBLE (-3425 3350);
FORCEPROP 1 LAST BODY_TYPE PLUMBING
J 0
(-3425 3400);
DISPLAY 0.872340 (-3425 3400);
PAINT GREEN (-3425 3400);
DISPLAY INVISIBLE (-3425 3400);
FORCEPROP 1 LAST HDL_TAP TRUE
J 0
(-3100 3225);
DISPLAY 0.872340 (-3100 3225);
DISPLAY INVISIBLE (-3100 3225);
FORCEPROP 1 LAST PATH I218
J 0
(-3427 3350);
DISPLAY 0.872340 (-3427 3350);
PAINT GREEN (-3427 3350);
DISPLAY INVISIBLE (-3427 3350);
FORCEADD TAP..1
(-3425 3450);
FORCEPROP 3 LASTPIN (-3475 3450) SIG_NAME M_G_CPU0_SB_DQ<15>
J 0
(-3465 3460);
DISPLAY 0.659574 (-3465 3460);
PAINT MONO (-3465 3460);
DISPLAY INVISIBLE (-3465 3460);
FORCEPROP 1 LASTPIN (-3475 3450) BN 15
J 0
(-3487 3458);
DISPLAY 0.489362 (-3487 3458);
PAINT GREEN (-3487 3458);
FORCEPROP 2 LAST CDS_LIB mstr_standard
J 0
(-3425 3450);
DISPLAY 0.723404 (-3425 3450);
PAINT MONO (-3425 3450);
DISPLAY INVISIBLE (-3425 3450);
FORCEPROP 1 LAST BODY_TYPE PLUMBING
J 0
(-3425 3500);
DISPLAY 0.872340 (-3425 3500);
PAINT GREEN (-3425 3500);
DISPLAY INVISIBLE (-3425 3500);
FORCEPROP 1 LAST HDL_TAP TRUE
J 0
(-3100 3325);
DISPLAY 0.872340 (-3100 3325);
DISPLAY INVISIBLE (-3100 3325);
FORCEPROP 1 LAST PATH I219
J 0
(-3427 3450);
DISPLAY 0.872340 (-3427 3450);
PAINT GREEN (-3427 3450);
DISPLAY INVISIBLE (-3427 3450);
FORCEADD TAP..1
(-3425 3300);
FORCEPROP 3 LASTPIN (-3475 3300) SIG_NAME M_G_CPU0_SB_DQ<17>
J 0
(-3465 3310);
DISPLAY 0.659574 (-3465 3310);
PAINT MONO (-3465 3310);
DISPLAY INVISIBLE (-3465 3310);
FORCEPROP 1 LASTPIN (-3475 3300) BN 17
J 0
(-3487 3308);
DISPLAY 0.489362 (-3487 3308);
PAINT GREEN (-3487 3308);
FORCEPROP 2 LAST CDS_LIB mstr_standard
J 0
(-3425 3300);
DISPLAY 0.723404 (-3425 3300);
PAINT MONO (-3425 3300);
DISPLAY INVISIBLE (-3425 3300);
FORCEPROP 1 LAST BODY_TYPE PLUMBING
J 0
(-3425 3350);
DISPLAY 0.872340 (-3425 3350);
PAINT GREEN (-3425 3350);
DISPLAY INVISIBLE (-3425 3350);
FORCEPROP 1 LAST HDL_TAP TRUE
J 0
(-3100 3175);
DISPLAY 0.872340 (-3100 3175);
DISPLAY INVISIBLE (-3100 3175);
FORCEPROP 1 LAST PATH I220
J 0
(-3427 3300);
DISPLAY 0.872340 (-3427 3300);
PAINT GREEN (-3427 3300);
DISPLAY INVISIBLE (-3427 3300);
FORCEADD TAP..1
(-3425 3250);
FORCEPROP 3 LASTPIN (-3475 3250) SIG_NAME M_G_CPU0_SB_DQ<18>
J 0
(-3465 3260);
DISPLAY 0.659574 (-3465 3260);
PAINT MONO (-3465 3260);
DISPLAY INVISIBLE (-3465 3260);
FORCEPROP 1 LASTPIN (-3475 3250) BN 18
J 0
(-3487 3258);
DISPLAY 0.489362 (-3487 3258);
PAINT GREEN (-3487 3258);
FORCEPROP 2 LAST CDS_LIB mstr_standard
J 0
(-3425 3250);
DISPLAY 0.723404 (-3425 3250);
PAINT MONO (-3425 3250);
DISPLAY INVISIBLE (-3425 3250);
FORCEPROP 1 LAST BODY_TYPE PLUMBING
J 0
(-3425 3300);
DISPLAY 0.872340 (-3425 3300);
PAINT GREEN (-3425 3300);
DISPLAY INVISIBLE (-3425 3300);
FORCEPROP 1 LAST HDL_TAP TRUE
J 0
(-3100 3125);
DISPLAY 0.872340 (-3100 3125);
DISPLAY INVISIBLE (-3100 3125);
FORCEPROP 1 LAST PATH I221
J 0
(-3427 3250);
DISPLAY 0.872340 (-3427 3250);
PAINT GREEN (-3427 3250);
DISPLAY INVISIBLE (-3427 3250);
FORCEADD TAP..1
(-3425 3200);
FORCEPROP 3 LASTPIN (-3475 3200) SIG_NAME M_G_CPU0_SB_DQ<19>
J 0
(-3465 3210);
DISPLAY 0.659574 (-3465 3210);
PAINT MONO (-3465 3210);
DISPLAY INVISIBLE (-3465 3210);
FORCEPROP 1 LASTPIN (-3475 3200) BN 19
J 0
(-3487 3208);
DISPLAY 0.489362 (-3487 3208);
PAINT GREEN (-3487 3208);
FORCEPROP 2 LAST CDS_LIB mstr_standard
J 0
(-3425 3200);
DISPLAY 0.723404 (-3425 3200);
PAINT MONO (-3425 3200);
DISPLAY INVISIBLE (-3425 3200);
FORCEPROP 1 LAST BODY_TYPE PLUMBING
J 0
(-3425 3250);
DISPLAY 0.872340 (-3425 3250);
PAINT GREEN (-3425 3250);
DISPLAY INVISIBLE (-3425 3250);
FORCEPROP 1 LAST HDL_TAP TRUE
J 0
(-3100 3075);
DISPLAY 0.872340 (-3100 3075);
DISPLAY INVISIBLE (-3100 3075);
FORCEPROP 1 LAST PATH I222
J 0
(-3427 3200);
DISPLAY 0.872340 (-3427 3200);
PAINT GREEN (-3427 3200);
DISPLAY INVISIBLE (-3427 3200);
FORCEADD TAP..1
(-3425 3150);
FORCEPROP 3 LASTPIN (-3475 3150) SIG_NAME M_G_CPU0_SB_DQ<20>
J 0
(-3465 3160);
DISPLAY 0.659574 (-3465 3160);
PAINT MONO (-3465 3160);
DISPLAY INVISIBLE (-3465 3160);
FORCEPROP 1 LASTPIN (-3475 3150) BN 20
J 0
(-3487 3158);
DISPLAY 0.489362 (-3487 3158);
PAINT GREEN (-3487 3158);
FORCEPROP 2 LAST CDS_LIB mstr_standard
J 0
(-3425 3150);
DISPLAY 0.723404 (-3425 3150);
PAINT MONO (-3425 3150);
DISPLAY INVISIBLE (-3425 3150);
FORCEPROP 1 LAST BODY_TYPE PLUMBING
J 0
(-3425 3200);
DISPLAY 0.872340 (-3425 3200);
PAINT GREEN (-3425 3200);
DISPLAY INVISIBLE (-3425 3200);
FORCEPROP 1 LAST HDL_TAP TRUE
J 0
(-3100 3025);
DISPLAY 0.872340 (-3100 3025);
DISPLAY INVISIBLE (-3100 3025);
FORCEPROP 1 LAST PATH I223
J 0
(-3427 3150);
DISPLAY 0.872340 (-3427 3150);
PAINT GREEN (-3427 3150);
DISPLAY INVISIBLE (-3427 3150);
FORCEADD TAP..1
(-3425 3100);
FORCEPROP 3 LASTPIN (-3475 3100) SIG_NAME M_G_CPU0_SB_DQ<21>
J 0
(-3465 3110);
DISPLAY 0.659574 (-3465 3110);
PAINT MONO (-3465 3110);
DISPLAY INVISIBLE (-3465 3110);
FORCEPROP 1 LASTPIN (-3475 3100) BN 21
J 0
(-3487 3108);
DISPLAY 0.489362 (-3487 3108);
PAINT GREEN (-3487 3108);
FORCEPROP 2 LAST CDS_LIB mstr_standard
J 0
(-3425 3100);
DISPLAY 0.723404 (-3425 3100);
PAINT MONO (-3425 3100);
DISPLAY INVISIBLE (-3425 3100);
FORCEPROP 1 LAST BODY_TYPE PLUMBING
J 0
(-3425 3150);
DISPLAY 0.872340 (-3425 3150);
PAINT GREEN (-3425 3150);
DISPLAY INVISIBLE (-3425 3150);
FORCEPROP 1 LAST HDL_TAP TRUE
J 0
(-3100 2975);
DISPLAY 0.872340 (-3100 2975);
DISPLAY INVISIBLE (-3100 2975);
FORCEPROP 1 LAST PATH I224
J 0
(-3427 3100);
DISPLAY 0.872340 (-3427 3100);
PAINT GREEN (-3427 3100);
DISPLAY INVISIBLE (-3427 3100);
FORCEADD TAP..1
(-3425 3050);
FORCEPROP 3 LASTPIN (-3475 3050) SIG_NAME M_G_CPU0_SB_DQ<22>
J 0
(-3465 3060);
DISPLAY 0.659574 (-3465 3060);
PAINT MONO (-3465 3060);
DISPLAY INVISIBLE (-3465 3060);
FORCEPROP 1 LASTPIN (-3475 3050) BN 22
J 0
(-3487 3058);
DISPLAY 0.489362 (-3487 3058);
PAINT GREEN (-3487 3058);
FORCEPROP 2 LAST CDS_LIB mstr_standard
J 0
(-3425 3050);
DISPLAY 0.723404 (-3425 3050);
PAINT MONO (-3425 3050);
DISPLAY INVISIBLE (-3425 3050);
FORCEPROP 1 LAST BODY_TYPE PLUMBING
J 0
(-3425 3100);
DISPLAY 0.872340 (-3425 3100);
PAINT GREEN (-3425 3100);
DISPLAY INVISIBLE (-3425 3100);
FORCEPROP 1 LAST HDL_TAP TRUE
J 0
(-3100 2925);
DISPLAY 0.872340 (-3100 2925);
DISPLAY INVISIBLE (-3100 2925);
FORCEPROP 1 LAST PATH I225
J 0
(-3427 3050);
DISPLAY 0.872340 (-3427 3050);
PAINT GREEN (-3427 3050);
DISPLAY INVISIBLE (-3427 3050);
FORCEADD TAP..1
(-3425 3000);
FORCEPROP 3 LASTPIN (-3475 3000) SIG_NAME M_G_CPU0_SB_DQ<23>
J 0
(-3465 3010);
DISPLAY 0.659574 (-3465 3010);
PAINT MONO (-3465 3010);
DISPLAY INVISIBLE (-3465 3010);
FORCEPROP 1 LASTPIN (-3475 3000) BN 23
J 0
(-3487 3008);
DISPLAY 0.489362 (-3487 3008);
PAINT GREEN (-3487 3008);
FORCEPROP 2 LAST CDS_LIB mstr_standard
J 0
(-3425 3000);
DISPLAY 0.723404 (-3425 3000);
PAINT MONO (-3425 3000);
DISPLAY INVISIBLE (-3425 3000);
FORCEPROP 1 LAST BODY_TYPE PLUMBING
J 0
(-3425 3050);
DISPLAY 0.872340 (-3425 3050);
PAINT GREEN (-3425 3050);
DISPLAY INVISIBLE (-3425 3050);
FORCEPROP 1 LAST HDL_TAP TRUE
J 0
(-3100 2875);
DISPLAY 0.872340 (-3100 2875);
DISPLAY INVISIBLE (-3100 2875);
FORCEPROP 1 LAST PATH I226
J 0
(-3427 3000);
DISPLAY 0.872340 (-3427 3000);
PAINT GREEN (-3427 3000);
DISPLAY INVISIBLE (-3427 3000);
FORCEADD TAP..1
(-3425 2900);
FORCEPROP 3 LASTPIN (-3475 2900) SIG_NAME M_G_CPU0_SB_DQ<24>
J 0
(-3465 2910);
DISPLAY 0.659574 (-3465 2910);
PAINT MONO (-3465 2910);
DISPLAY INVISIBLE (-3465 2910);
FORCEPROP 1 LASTPIN (-3475 2900) BN 24
J 0
(-3487 2908);
DISPLAY 0.489362 (-3487 2908);
PAINT GREEN (-3487 2908);
FORCEPROP 2 LAST CDS_LIB mstr_standard
J 0
(-3425 2900);
DISPLAY 0.723404 (-3425 2900);
PAINT MONO (-3425 2900);
DISPLAY INVISIBLE (-3425 2900);
FORCEPROP 1 LAST BODY_TYPE PLUMBING
J 0
(-3425 2950);
DISPLAY 0.872340 (-3425 2950);
PAINT GREEN (-3425 2950);
DISPLAY INVISIBLE (-3425 2950);
FORCEPROP 1 LAST HDL_TAP TRUE
J 0
(-3100 2775);
DISPLAY 0.872340 (-3100 2775);
DISPLAY INVISIBLE (-3100 2775);
FORCEPROP 1 LAST PATH I227
J 0
(-3427 2900);
DISPLAY 0.872340 (-3427 2900);
PAINT GREEN (-3427 2900);
DISPLAY INVISIBLE (-3427 2900);
FORCEADD TAP..1
(-3425 2850);
FORCEPROP 3 LASTPIN (-3475 2850) SIG_NAME M_G_CPU0_SB_DQ<25>
J 0
(-3465 2860);
DISPLAY 0.659574 (-3465 2860);
PAINT MONO (-3465 2860);
DISPLAY INVISIBLE (-3465 2860);
FORCEPROP 1 LASTPIN (-3475 2850) BN 25
J 0
(-3487 2858);
DISPLAY 0.489362 (-3487 2858);
PAINT GREEN (-3487 2858);
FORCEPROP 2 LAST CDS_LIB mstr_standard
J 0
(-3425 2850);
DISPLAY 0.723404 (-3425 2850);
PAINT MONO (-3425 2850);
DISPLAY INVISIBLE (-3425 2850);
FORCEPROP 1 LAST BODY_TYPE PLUMBING
J 0
(-3425 2900);
DISPLAY 0.872340 (-3425 2900);
PAINT GREEN (-3425 2900);
DISPLAY INVISIBLE (-3425 2900);
FORCEPROP 1 LAST HDL_TAP TRUE
J 0
(-3100 2725);
DISPLAY 0.872340 (-3100 2725);
DISPLAY INVISIBLE (-3100 2725);
FORCEPROP 1 LAST PATH I228
J 0
(-3427 2850);
DISPLAY 0.872340 (-3427 2850);
PAINT GREEN (-3427 2850);
DISPLAY INVISIBLE (-3427 2850);
FORCEADD TAP..1
(-3425 2800);
FORCEPROP 3 LASTPIN (-3475 2800) SIG_NAME M_G_CPU0_SB_DQ<26>
J 0
(-3465 2810);
DISPLAY 0.659574 (-3465 2810);
PAINT MONO (-3465 2810);
DISPLAY INVISIBLE (-3465 2810);
FORCEPROP 1 LASTPIN (-3475 2800) BN 26
J 0
(-3487 2808);
DISPLAY 0.489362 (-3487 2808);
PAINT GREEN (-3487 2808);
FORCEPROP 2 LAST CDS_LIB mstr_standard
J 0
(-3425 2800);
DISPLAY 0.723404 (-3425 2800);
PAINT MONO (-3425 2800);
DISPLAY INVISIBLE (-3425 2800);
FORCEPROP 1 LAST BODY_TYPE PLUMBING
J 0
(-3425 2850);
DISPLAY 0.872340 (-3425 2850);
PAINT GREEN (-3425 2850);
DISPLAY INVISIBLE (-3425 2850);
FORCEPROP 1 LAST HDL_TAP TRUE
J 0
(-3100 2675);
DISPLAY 0.872340 (-3100 2675);
DISPLAY INVISIBLE (-3100 2675);
FORCEPROP 1 LAST PATH I229
J 0
(-3427 2800);
DISPLAY 0.872340 (-3427 2800);
PAINT GREEN (-3427 2800);
DISPLAY INVISIBLE (-3427 2800);
FORCEADD TAP..1
(-3425 2750);
FORCEPROP 3 LASTPIN (-3475 2750) SIG_NAME M_G_CPU0_SB_DQ<27>
J 0
(-3465 2760);
DISPLAY 0.659574 (-3465 2760);
PAINT MONO (-3465 2760);
DISPLAY INVISIBLE (-3465 2760);
FORCEPROP 1 LASTPIN (-3475 2750) BN 27
J 0
(-3487 2758);
DISPLAY 0.489362 (-3487 2758);
PAINT GREEN (-3487 2758);
FORCEPROP 2 LAST CDS_LIB mstr_standard
J 0
(-3425 2750);
DISPLAY 0.723404 (-3425 2750);
PAINT MONO (-3425 2750);
DISPLAY INVISIBLE (-3425 2750);
FORCEPROP 1 LAST BODY_TYPE PLUMBING
J 0
(-3425 2800);
DISPLAY 0.872340 (-3425 2800);
PAINT GREEN (-3425 2800);
DISPLAY INVISIBLE (-3425 2800);
FORCEPROP 1 LAST HDL_TAP TRUE
J 0
(-3100 2625);
DISPLAY 0.872340 (-3100 2625);
DISPLAY INVISIBLE (-3100 2625);
FORCEPROP 1 LAST PATH I230
J 0
(-3427 2750);
DISPLAY 0.872340 (-3427 2750);
PAINT GREEN (-3427 2750);
DISPLAY INVISIBLE (-3427 2750);
FORCEADD TAP..1
(-3425 2700);
FORCEPROP 3 LASTPIN (-3475 2700) SIG_NAME M_G_CPU0_SB_DQ<28>
J 0
(-3465 2710);
DISPLAY 0.659574 (-3465 2710);
PAINT MONO (-3465 2710);
DISPLAY INVISIBLE (-3465 2710);
FORCEPROP 1 LASTPIN (-3475 2700) BN 28
J 0
(-3487 2708);
DISPLAY 0.489362 (-3487 2708);
PAINT GREEN (-3487 2708);
FORCEPROP 2 LAST CDS_LIB mstr_standard
J 0
(-3425 2700);
DISPLAY 0.723404 (-3425 2700);
PAINT MONO (-3425 2700);
DISPLAY INVISIBLE (-3425 2700);
FORCEPROP 1 LAST BODY_TYPE PLUMBING
J 0
(-3425 2750);
DISPLAY 0.872340 (-3425 2750);
PAINT GREEN (-3425 2750);
DISPLAY INVISIBLE (-3425 2750);
FORCEPROP 1 LAST HDL_TAP TRUE
J 0
(-3100 2575);
DISPLAY 0.872340 (-3100 2575);
DISPLAY INVISIBLE (-3100 2575);
FORCEPROP 1 LAST PATH I231
J 0
(-3427 2700);
DISPLAY 0.872340 (-3427 2700);
PAINT GREEN (-3427 2700);
DISPLAY INVISIBLE (-3427 2700);
FORCEADD TAP..1
(-3425 2650);
FORCEPROP 3 LASTPIN (-3475 2650) SIG_NAME M_G_CPU0_SB_DQ<29>
J 0
(-3465 2660);
DISPLAY 0.659574 (-3465 2660);
PAINT MONO (-3465 2660);
DISPLAY INVISIBLE (-3465 2660);
FORCEPROP 1 LASTPIN (-3475 2650) BN 29
J 0
(-3487 2658);
DISPLAY 0.489362 (-3487 2658);
PAINT GREEN (-3487 2658);
FORCEPROP 2 LAST CDS_LIB mstr_standard
J 0
(-3425 2650);
DISPLAY 0.723404 (-3425 2650);
PAINT MONO (-3425 2650);
DISPLAY INVISIBLE (-3425 2650);
FORCEPROP 1 LAST BODY_TYPE PLUMBING
J 0
(-3425 2700);
DISPLAY 0.872340 (-3425 2700);
PAINT GREEN (-3425 2700);
DISPLAY INVISIBLE (-3425 2700);
FORCEPROP 1 LAST HDL_TAP TRUE
J 0
(-3100 2525);
DISPLAY 0.872340 (-3100 2525);
DISPLAY INVISIBLE (-3100 2525);
FORCEPROP 1 LAST PATH I232
J 0
(-3427 2650);
DISPLAY 0.872340 (-3427 2650);
PAINT GREEN (-3427 2650);
DISPLAY INVISIBLE (-3427 2650);
FORCEADD TAP..1
(-3425 2600);
FORCEPROP 3 LASTPIN (-3475 2600) SIG_NAME M_G_CPU0_SB_DQ<30>
J 0
(-3465 2610);
DISPLAY 0.659574 (-3465 2610);
PAINT MONO (-3465 2610);
DISPLAY INVISIBLE (-3465 2610);
FORCEPROP 1 LASTPIN (-3475 2600) BN 30
J 0
(-3487 2608);
DISPLAY 0.489362 (-3487 2608);
PAINT GREEN (-3487 2608);
FORCEPROP 2 LAST CDS_LIB mstr_standard
J 0
(-3425 2600);
DISPLAY 0.723404 (-3425 2600);
PAINT MONO (-3425 2600);
DISPLAY INVISIBLE (-3425 2600);
FORCEPROP 1 LAST BODY_TYPE PLUMBING
J 0
(-3425 2650);
DISPLAY 0.872340 (-3425 2650);
PAINT GREEN (-3425 2650);
DISPLAY INVISIBLE (-3425 2650);
FORCEPROP 1 LAST HDL_TAP TRUE
J 0
(-3100 2475);
DISPLAY 0.872340 (-3100 2475);
DISPLAY INVISIBLE (-3100 2475);
FORCEPROP 1 LAST PATH I233
J 0
(-3427 2600);
DISPLAY 0.872340 (-3427 2600);
PAINT GREEN (-3427 2600);
DISPLAY INVISIBLE (-3427 2600);
FORCEADD TAP..1
(-3425 2450);
FORCEPROP 3 LASTPIN (-3475 2450) SIG_NAME M_G_CPU0_SA_CB<0>
J 0
(-3465 2460);
DISPLAY 0.659574 (-3465 2460);
PAINT MONO (-3465 2460);
DISPLAY INVISIBLE (-3465 2460);
FORCEPROP 1 LASTPIN (-3475 2450) BN 0
J 0
(-3487 2458);
DISPLAY 0.489362 (-3487 2458);
PAINT GREEN (-3487 2458);
FORCEPROP 2 LAST CDS_LIB mstr_standard
J 2
(-3425 2450);
DISPLAY 0.723404 (-3425 2450);
PAINT MONO (-3425 2450);
DISPLAY INVISIBLE (-3425 2450);
FORCEPROP 1 LAST BODY_TYPE PLUMBING
J 0
(-3425 2500);
DISPLAY 0.872340 (-3425 2500);
PAINT GREEN (-3425 2500);
DISPLAY INVISIBLE (-3425 2500);
FORCEPROP 1 LAST HDL_TAP TRUE
J 0
(-3100 2325);
DISPLAY 0.872340 (-3100 2325);
DISPLAY INVISIBLE (-3100 2325);
FORCEPROP 1 LAST PATH I234
J 0
(-3427 2450);
DISPLAY 0.872340 (-3427 2450);
PAINT GREEN (-3427 2450);
DISPLAY INVISIBLE (-3427 2450);
FORCEADD TAP..1
(-3425 2550);
FORCEPROP 3 LASTPIN (-3475 2550) SIG_NAME M_G_CPU0_SB_DQ<31>
J 0
(-3465 2560);
DISPLAY 0.659574 (-3465 2560);
PAINT MONO (-3465 2560);
DISPLAY INVISIBLE (-3465 2560);
FORCEPROP 1 LASTPIN (-3475 2550) BN 31
J 0
(-3487 2558);
DISPLAY 0.489362 (-3487 2558);
PAINT GREEN (-3487 2558);
FORCEPROP 2 LAST CDS_LIB mstr_standard
J 0
(-3425 2550);
DISPLAY 0.723404 (-3425 2550);
PAINT MONO (-3425 2550);
DISPLAY INVISIBLE (-3425 2550);
FORCEPROP 1 LAST BODY_TYPE PLUMBING
J 0
(-3425 2600);
DISPLAY 0.872340 (-3425 2600);
PAINT GREEN (-3425 2600);
DISPLAY INVISIBLE (-3425 2600);
FORCEPROP 1 LAST HDL_TAP TRUE
J 0
(-3100 2425);
DISPLAY 0.872340 (-3100 2425);
DISPLAY INVISIBLE (-3100 2425);
FORCEPROP 1 LAST PATH I235
J 0
(-3427 2550);
DISPLAY 0.872340 (-3427 2550);
PAINT GREEN (-3427 2550);
DISPLAY INVISIBLE (-3427 2550);
FORCEADD TAP..1
(-3425 2400);
FORCEPROP 3 LASTPIN (-3475 2400) SIG_NAME M_G_CPU0_SA_CB<1>
J 0
(-3465 2410);
DISPLAY 0.659574 (-3465 2410);
PAINT MONO (-3465 2410);
DISPLAY INVISIBLE (-3465 2410);
FORCEPROP 1 LASTPIN (-3475 2400) BN 1
J 0
(-3487 2408);
DISPLAY 0.489362 (-3487 2408);
PAINT GREEN (-3487 2408);
FORCEPROP 2 LAST CDS_LIB mstr_standard
J 2
(-3425 2400);
DISPLAY 0.723404 (-3425 2400);
PAINT MONO (-3425 2400);
DISPLAY INVISIBLE (-3425 2400);
FORCEPROP 1 LAST BODY_TYPE PLUMBING
J 0
(-3425 2450);
DISPLAY 0.872340 (-3425 2450);
PAINT GREEN (-3425 2450);
DISPLAY INVISIBLE (-3425 2450);
FORCEPROP 1 LAST HDL_TAP TRUE
J 0
(-3100 2275);
DISPLAY 0.872340 (-3100 2275);
DISPLAY INVISIBLE (-3100 2275);
FORCEPROP 1 LAST PATH I236
J 0
(-3427 2400);
DISPLAY 0.872340 (-3427 2400);
PAINT GREEN (-3427 2400);
DISPLAY INVISIBLE (-3427 2400);
FORCEADD TAP..1
(-3425 2350);
FORCEPROP 3 LASTPIN (-3475 2350) SIG_NAME M_G_CPU0_SA_CB<2>
J 0
(-3465 2360);
DISPLAY 0.659574 (-3465 2360);
PAINT MONO (-3465 2360);
DISPLAY INVISIBLE (-3465 2360);
FORCEPROP 1 LASTPIN (-3475 2350) BN 2
J 0
(-3487 2358);
DISPLAY 0.489362 (-3487 2358);
PAINT GREEN (-3487 2358);
FORCEPROP 2 LAST CDS_LIB mstr_standard
J 2
(-3425 2350);
DISPLAY 0.723404 (-3425 2350);
PAINT MONO (-3425 2350);
DISPLAY INVISIBLE (-3425 2350);
FORCEPROP 1 LAST BODY_TYPE PLUMBING
J 0
(-3425 2400);
DISPLAY 0.872340 (-3425 2400);
PAINT GREEN (-3425 2400);
DISPLAY INVISIBLE (-3425 2400);
FORCEPROP 1 LAST HDL_TAP TRUE
J 0
(-3100 2225);
DISPLAY 0.872340 (-3100 2225);
DISPLAY INVISIBLE (-3100 2225);
FORCEPROP 1 LAST PATH I237
J 0
(-3427 2350);
DISPLAY 0.872340 (-3427 2350);
PAINT GREEN (-3427 2350);
DISPLAY INVISIBLE (-3427 2350);
FORCEADD TAP..1
(-3425 2250);
FORCEPROP 3 LASTPIN (-3475 2250) SIG_NAME M_G_CPU0_SA_CB<4>
J 0
(-3465 2260);
DISPLAY 0.659574 (-3465 2260);
PAINT MONO (-3465 2260);
DISPLAY INVISIBLE (-3465 2260);
FORCEPROP 1 LASTPIN (-3475 2250) BN 4
J 0
(-3487 2258);
DISPLAY 0.489362 (-3487 2258);
PAINT GREEN (-3487 2258);
FORCEPROP 2 LAST CDS_LIB mstr_standard
J 2
(-3425 2250);
DISPLAY 0.723404 (-3425 2250);
PAINT MONO (-3425 2250);
DISPLAY INVISIBLE (-3425 2250);
FORCEPROP 1 LAST BODY_TYPE PLUMBING
J 0
(-3425 2300);
DISPLAY 0.872340 (-3425 2300);
PAINT GREEN (-3425 2300);
DISPLAY INVISIBLE (-3425 2300);
FORCEPROP 1 LAST HDL_TAP TRUE
J 0
(-3100 2125);
DISPLAY 0.872340 (-3100 2125);
DISPLAY INVISIBLE (-3100 2125);
FORCEPROP 1 LAST PATH I238
J 0
(-3427 2250);
DISPLAY 0.872340 (-3427 2250);
PAINT GREEN (-3427 2250);
DISPLAY INVISIBLE (-3427 2250);
FORCEADD TAP..1
(-3425 2300);
FORCEPROP 3 LASTPIN (-3475 2300) SIG_NAME M_G_CPU0_SA_CB<3>
J 0
(-3465 2310);
DISPLAY 0.659574 (-3465 2310);
PAINT MONO (-3465 2310);
DISPLAY INVISIBLE (-3465 2310);
FORCEPROP 1 LASTPIN (-3475 2300) BN 3
J 0
(-3487 2308);
DISPLAY 0.489362 (-3487 2308);
PAINT GREEN (-3487 2308);
FORCEPROP 2 LAST CDS_LIB mstr_standard
J 2
(-3425 2300);
DISPLAY 0.723404 (-3425 2300);
PAINT MONO (-3425 2300);
DISPLAY INVISIBLE (-3425 2300);
FORCEPROP 1 LAST BODY_TYPE PLUMBING
J 0
(-3425 2350);
DISPLAY 0.872340 (-3425 2350);
PAINT GREEN (-3425 2350);
DISPLAY INVISIBLE (-3425 2350);
FORCEPROP 1 LAST HDL_TAP TRUE
J 0
(-3100 2175);
DISPLAY 0.872340 (-3100 2175);
DISPLAY INVISIBLE (-3100 2175);
FORCEPROP 1 LAST PATH I239
J 0
(-3427 2300);
DISPLAY 0.872340 (-3427 2300);
PAINT GREEN (-3427 2300);
DISPLAY INVISIBLE (-3427 2300);
FORCEADD TAP..1
(-3425 2200);
FORCEPROP 3 LASTPIN (-3475 2200) SIG_NAME M_G_CPU0_SA_CB<5>
J 0
(-3465 2210);
DISPLAY 0.659574 (-3465 2210);
PAINT MONO (-3465 2210);
DISPLAY INVISIBLE (-3465 2210);
FORCEPROP 1 LASTPIN (-3475 2200) BN 5
J 0
(-3487 2208);
DISPLAY 0.489362 (-3487 2208);
PAINT GREEN (-3487 2208);
FORCEPROP 2 LAST CDS_LIB mstr_standard
J 2
(-3425 2200);
DISPLAY 0.723404 (-3425 2200);
PAINT MONO (-3425 2200);
DISPLAY INVISIBLE (-3425 2200);
FORCEPROP 1 LAST BODY_TYPE PLUMBING
J 0
(-3425 2250);
DISPLAY 0.872340 (-3425 2250);
PAINT GREEN (-3425 2250);
DISPLAY INVISIBLE (-3425 2250);
FORCEPROP 1 LAST HDL_TAP TRUE
J 0
(-3100 2075);
DISPLAY 0.872340 (-3100 2075);
DISPLAY INVISIBLE (-3100 2075);
FORCEPROP 1 LAST PATH I240
J 0
(-3427 2200);
DISPLAY 0.872340 (-3427 2200);
PAINT GREEN (-3427 2200);
DISPLAY INVISIBLE (-3427 2200);
FORCEADD TAP..1
(-3425 2100);
FORCEPROP 3 LASTPIN (-3475 2100) SIG_NAME M_G_CPU0_SA_CB<7>
J 0
(-3465 2110);
DISPLAY 0.659574 (-3465 2110);
PAINT MONO (-3465 2110);
DISPLAY INVISIBLE (-3465 2110);
FORCEPROP 1 LASTPIN (-3475 2100) BN 7
J 0
(-3487 2108);
DISPLAY 0.489362 (-3487 2108);
PAINT GREEN (-3487 2108);
FORCEPROP 2 LAST CDS_LIB mstr_standard
J 2
(-3425 2100);
DISPLAY 0.723404 (-3425 2100);
PAINT MONO (-3425 2100);
DISPLAY INVISIBLE (-3425 2100);
FORCEPROP 1 LAST BODY_TYPE PLUMBING
J 0
(-3425 2150);
DISPLAY 0.872340 (-3425 2150);
PAINT GREEN (-3425 2150);
DISPLAY INVISIBLE (-3425 2150);
FORCEPROP 1 LAST HDL_TAP TRUE
J 0
(-3100 1975);
DISPLAY 0.872340 (-3100 1975);
DISPLAY INVISIBLE (-3100 1975);
FORCEPROP 1 LAST PATH I241
J 0
(-3427 2100);
DISPLAY 0.872340 (-3427 2100);
PAINT GREEN (-3427 2100);
DISPLAY INVISIBLE (-3427 2100);
FORCEADD TAP..1
(-3425 2150);
FORCEPROP 3 LASTPIN (-3475 2150) SIG_NAME M_G_CPU0_SA_CB<6>
J 0
(-3465 2160);
DISPLAY 0.659574 (-3465 2160);
PAINT MONO (-3465 2160);
DISPLAY INVISIBLE (-3465 2160);
FORCEPROP 1 LASTPIN (-3475 2150) BN 6
J 0
(-3487 2158);
DISPLAY 0.489362 (-3487 2158);
PAINT GREEN (-3487 2158);
FORCEPROP 2 LAST CDS_LIB mstr_standard
J 2
(-3425 2150);
DISPLAY 0.723404 (-3425 2150);
PAINT MONO (-3425 2150);
DISPLAY INVISIBLE (-3425 2150);
FORCEPROP 1 LAST BODY_TYPE PLUMBING
J 0
(-3425 2200);
DISPLAY 0.872340 (-3425 2200);
PAINT GREEN (-3425 2200);
DISPLAY INVISIBLE (-3425 2200);
FORCEPROP 1 LAST HDL_TAP TRUE
J 0
(-3100 2025);
DISPLAY 0.872340 (-3100 2025);
DISPLAY INVISIBLE (-3100 2025);
FORCEPROP 1 LAST PATH I242
J 0
(-3427 2150);
DISPLAY 0.872340 (-3427 2150);
PAINT GREEN (-3427 2150);
DISPLAY INVISIBLE (-3427 2150);
FORCEADD OFFPAGE..6
R 2
(-2825 2050);
FORCEPROP 2 LAST $XR0 92 
J 0
(-2611 2050);
DISPLAY 0.638298 (-2611 2050);
PAINT MONO (-2611 2050);
FORCEPROP 2 LAST CDS_LIB mstr_standard
J 2
(-2825 2050);
DISPLAY 0.723404 (-2825 2050);
PAINT MONO (-2825 2050);
DISPLAY INVISIBLE (-2825 2050);
FORCEPROP 1 LAST OFFPAGE TRUE
J 2
(-3150 1925);
DISPLAY 0.872340 (-3150 1925);
PAINT GREEN (-3150 1925);
DISPLAY INVISIBLE (-3150 1925);
FORCEPROP 1 LAST COMMENT_BODY TRUE
J 2
(-2925 1975);
DISPLAY 0.872340 (-2925 1975);
PAINT GREEN (-2925 1975);
DISPLAY INVISIBLE (-2925 1975);
FORCEPROP 2 LAST PATH I243
J 0
(-2600 2100);
DISPLAY 1.021277 (-2600 2100);
DISPLAY INVISIBLE (-2600 2100);
FORCEADD TAP..1
(-3425 2000);
FORCEPROP 3 LASTPIN (-3475 2000) SIG_NAME M_G_CPU0_SB_CB<0>
J 0
(-3465 2010);
DISPLAY 0.659574 (-3465 2010);
PAINT MONO (-3465 2010);
DISPLAY INVISIBLE (-3465 2010);
FORCEPROP 1 LASTPIN (-3475 2000) BN 0
J 0
(-3487 2008);
DISPLAY 0.489362 (-3487 2008);
PAINT GREEN (-3487 2008);
FORCEPROP 2 LAST CDS_LIB mstr_standard
J 2
(-3425 2000);
DISPLAY 0.723404 (-3425 2000);
PAINT MONO (-3425 2000);
DISPLAY INVISIBLE (-3425 2000);
FORCEPROP 1 LAST BODY_TYPE PLUMBING
J 0
(-3425 2050);
DISPLAY 0.872340 (-3425 2050);
PAINT GREEN (-3425 2050);
DISPLAY INVISIBLE (-3425 2050);
FORCEPROP 1 LAST HDL_TAP TRUE
J 0
(-3100 1875);
DISPLAY 0.872340 (-3100 1875);
DISPLAY INVISIBLE (-3100 1875);
FORCEPROP 1 LAST PATH I244
J 0
(-3427 2000);
DISPLAY 0.872340 (-3427 2000);
PAINT GREEN (-3427 2000);
DISPLAY INVISIBLE (-3427 2000);
FORCEADD TAP..1
(-3425 1950);
FORCEPROP 3 LASTPIN (-3475 1950) SIG_NAME M_G_CPU0_SB_CB<1>
J 0
(-3465 1960);
DISPLAY 0.659574 (-3465 1960);
PAINT MONO (-3465 1960);
DISPLAY INVISIBLE (-3465 1960);
FORCEPROP 1 LASTPIN (-3475 1950) BN 1
J 0
(-3487 1958);
DISPLAY 0.489362 (-3487 1958);
PAINT GREEN (-3487 1958);
FORCEPROP 2 LAST CDS_LIB mstr_standard
J 2
(-3425 1950);
DISPLAY 0.723404 (-3425 1950);
PAINT MONO (-3425 1950);
DISPLAY INVISIBLE (-3425 1950);
FORCEPROP 1 LAST BODY_TYPE PLUMBING
J 0
(-3425 2000);
DISPLAY 0.872340 (-3425 2000);
PAINT GREEN (-3425 2000);
DISPLAY INVISIBLE (-3425 2000);
FORCEPROP 1 LAST HDL_TAP TRUE
J 0
(-3100 1825);
DISPLAY 0.872340 (-3100 1825);
DISPLAY INVISIBLE (-3100 1825);
FORCEPROP 1 LAST PATH I245
J 0
(-3427 1950);
DISPLAY 0.872340 (-3427 1950);
PAINT GREEN (-3427 1950);
DISPLAY INVISIBLE (-3427 1950);
FORCEADD TAP..1
(-3425 1900);
FORCEPROP 3 LASTPIN (-3475 1900) SIG_NAME M_G_CPU0_SB_CB<2>
J 0
(-3465 1910);
DISPLAY 0.659574 (-3465 1910);
PAINT MONO (-3465 1910);
DISPLAY INVISIBLE (-3465 1910);
FORCEPROP 1 LASTPIN (-3475 1900) BN 2
J 0
(-3487 1908);
DISPLAY 0.489362 (-3487 1908);
PAINT GREEN (-3487 1908);
FORCEPROP 2 LAST CDS_LIB mstr_standard
J 2
(-3425 1900);
DISPLAY 0.723404 (-3425 1900);
PAINT MONO (-3425 1900);
DISPLAY INVISIBLE (-3425 1900);
FORCEPROP 1 LAST BODY_TYPE PLUMBING
J 0
(-3425 1950);
DISPLAY 0.872340 (-3425 1950);
PAINT GREEN (-3425 1950);
DISPLAY INVISIBLE (-3425 1950);
FORCEPROP 1 LAST HDL_TAP TRUE
J 0
(-3100 1775);
DISPLAY 0.872340 (-3100 1775);
DISPLAY INVISIBLE (-3100 1775);
FORCEPROP 1 LAST PATH I246
J 0
(-3427 1900);
DISPLAY 0.872340 (-3427 1900);
PAINT GREEN (-3427 1900);
DISPLAY INVISIBLE (-3427 1900);
FORCEADD TAP..1
(-3425 1850);
FORCEPROP 3 LASTPIN (-3475 1850) SIG_NAME M_G_CPU0_SB_CB<3>
J 0
(-3465 1860);
DISPLAY 0.659574 (-3465 1860);
PAINT MONO (-3465 1860);
DISPLAY INVISIBLE (-3465 1860);
FORCEPROP 1 LASTPIN (-3475 1850) BN 3
J 0
(-3487 1858);
DISPLAY 0.489362 (-3487 1858);
PAINT GREEN (-3487 1858);
FORCEPROP 2 LAST CDS_LIB mstr_standard
J 2
(-3425 1850);
DISPLAY 0.723404 (-3425 1850);
PAINT MONO (-3425 1850);
DISPLAY INVISIBLE (-3425 1850);
FORCEPROP 1 LAST BODY_TYPE PLUMBING
J 0
(-3425 1900);
DISPLAY 0.872340 (-3425 1900);
PAINT GREEN (-3425 1900);
DISPLAY INVISIBLE (-3425 1900);
FORCEPROP 1 LAST HDL_TAP TRUE
J 0
(-3100 1725);
DISPLAY 0.872340 (-3100 1725);
DISPLAY INVISIBLE (-3100 1725);
FORCEPROP 1 LAST PATH I247
J 0
(-3427 1850);
DISPLAY 0.872340 (-3427 1850);
PAINT GREEN (-3427 1850);
DISPLAY INVISIBLE (-3427 1850);
FORCEADD TAP..1
(-3425 1800);
FORCEPROP 3 LASTPIN (-3475 1800) SIG_NAME M_G_CPU0_SB_CB<4>
J 0
(-3465 1810);
DISPLAY 0.659574 (-3465 1810);
PAINT MONO (-3465 1810);
DISPLAY INVISIBLE (-3465 1810);
FORCEPROP 1 LASTPIN (-3475 1800) BN 4
J 0
(-3487 1808);
DISPLAY 0.489362 (-3487 1808);
PAINT GREEN (-3487 1808);
FORCEPROP 2 LAST CDS_LIB mstr_standard
J 2
(-3425 1800);
DISPLAY 0.723404 (-3425 1800);
PAINT MONO (-3425 1800);
DISPLAY INVISIBLE (-3425 1800);
FORCEPROP 1 LAST BODY_TYPE PLUMBING
J 0
(-3425 1850);
DISPLAY 0.872340 (-3425 1850);
PAINT GREEN (-3425 1850);
DISPLAY INVISIBLE (-3425 1850);
FORCEPROP 1 LAST HDL_TAP TRUE
J 0
(-3100 1675);
DISPLAY 0.872340 (-3100 1675);
DISPLAY INVISIBLE (-3100 1675);
FORCEPROP 1 LAST PATH I248
J 0
(-3427 1800);
DISPLAY 0.872340 (-3427 1800);
PAINT GREEN (-3427 1800);
DISPLAY INVISIBLE (-3427 1800);
FORCEADD TAP..1
(-3425 1750);
FORCEPROP 3 LASTPIN (-3475 1750) SIG_NAME M_G_CPU0_SB_CB<5>
J 0
(-3465 1760);
DISPLAY 0.659574 (-3465 1760);
PAINT MONO (-3465 1760);
DISPLAY INVISIBLE (-3465 1760);
FORCEPROP 1 LASTPIN (-3475 1750) BN 5
J 0
(-3487 1758);
DISPLAY 0.489362 (-3487 1758);
PAINT GREEN (-3487 1758);
FORCEPROP 2 LAST CDS_LIB mstr_standard
J 2
(-3425 1750);
DISPLAY 0.723404 (-3425 1750);
PAINT MONO (-3425 1750);
DISPLAY INVISIBLE (-3425 1750);
FORCEPROP 1 LAST BODY_TYPE PLUMBING
J 0
(-3425 1800);
DISPLAY 0.872340 (-3425 1800);
PAINT GREEN (-3425 1800);
DISPLAY INVISIBLE (-3425 1800);
FORCEPROP 1 LAST HDL_TAP TRUE
J 0
(-3100 1625);
DISPLAY 0.872340 (-3100 1625);
DISPLAY INVISIBLE (-3100 1625);
FORCEPROP 1 LAST PATH I249
J 0
(-3427 1750);
DISPLAY 0.872340 (-3427 1750);
PAINT GREEN (-3427 1750);
DISPLAY INVISIBLE (-3427 1750);
FORCEADD TAP..1
(-3425 1700);
FORCEPROP 3 LASTPIN (-3475 1700) SIG_NAME M_G_CPU0_SB_CB<6>
J 0
(-3465 1710);
DISPLAY 0.659574 (-3465 1710);
PAINT MONO (-3465 1710);
DISPLAY INVISIBLE (-3465 1710);
FORCEPROP 1 LASTPIN (-3475 1700) BN 6
J 0
(-3487 1708);
DISPLAY 0.489362 (-3487 1708);
PAINT GREEN (-3487 1708);
FORCEPROP 2 LAST CDS_LIB mstr_standard
J 2
(-3425 1700);
DISPLAY 0.723404 (-3425 1700);
PAINT MONO (-3425 1700);
DISPLAY INVISIBLE (-3425 1700);
FORCEPROP 1 LAST BODY_TYPE PLUMBING
J 0
(-3425 1750);
DISPLAY 0.872340 (-3425 1750);
PAINT GREEN (-3425 1750);
DISPLAY INVISIBLE (-3425 1750);
FORCEPROP 1 LAST HDL_TAP TRUE
J 0
(-3100 1575);
DISPLAY 0.872340 (-3100 1575);
DISPLAY INVISIBLE (-3100 1575);
FORCEPROP 1 LAST PATH I250
J 0
(-3427 1700);
DISPLAY 0.872340 (-3427 1700);
PAINT GREEN (-3427 1700);
DISPLAY INVISIBLE (-3427 1700);
FORCEADD TAP..1
(-3425 1650);
FORCEPROP 3 LASTPIN (-3475 1650) SIG_NAME M_G_CPU0_SB_CB<7>
J 0
(-3465 1660);
DISPLAY 0.659574 (-3465 1660);
PAINT MONO (-3465 1660);
DISPLAY INVISIBLE (-3465 1660);
FORCEPROP 1 LASTPIN (-3475 1650) BN 7
J 0
(-3487 1658);
DISPLAY 0.489362 (-3487 1658);
PAINT GREEN (-3487 1658);
FORCEPROP 2 LAST CDS_LIB mstr_standard
J 2
(-3425 1650);
DISPLAY 0.723404 (-3425 1650);
PAINT MONO (-3425 1650);
DISPLAY INVISIBLE (-3425 1650);
FORCEPROP 1 LAST BODY_TYPE PLUMBING
J 0
(-3425 1700);
DISPLAY 0.872340 (-3425 1700);
PAINT GREEN (-3425 1700);
DISPLAY INVISIBLE (-3425 1700);
FORCEPROP 1 LAST HDL_TAP TRUE
J 0
(-3100 1525);
DISPLAY 0.872340 (-3100 1525);
DISPLAY INVISIBLE (-3100 1525);
FORCEPROP 1 LAST PATH I251
J 0
(-3427 1650);
DISPLAY 0.872340 (-3427 1650);
PAINT GREEN (-3427 1650);
DISPLAY INVISIBLE (-3427 1650);
FORCEADD TAP..1
R 2
(-5850 6050);
FORCEPROP 3 LASTPIN (-5800 6050) SIG_NAME M_G_CPU0_SA_DQS_DP<0>
J 0
(-5790 6060);
DISPLAY 0.659574 (-5790 6060);
PAINT MONO (-5790 6060);
DISPLAY INVISIBLE (-5790 6060);
FORCEPROP 1 LASTPIN (-5800 6050) BN 0
J 2
(-5788 6058);
DISPLAY 0.489362 (-5788 6058);
PAINT GREEN (-5788 6058);
FORCEPROP 2 LAST CDS_LIB mstr_standard
J 2
(-5850 6050);
DISPLAY 0.723404 (-5850 6050);
PAINT MONO (-5850 6050);
DISPLAY INVISIBLE (-5850 6050);
FORCEPROP 1 LAST BODY_TYPE PLUMBING
J 2
(-5850 6100);
DISPLAY 0.872340 (-5850 6100);
PAINT GREEN (-5850 6100);
DISPLAY INVISIBLE (-5850 6100);
FORCEPROP 1 LAST HDL_TAP TRUE
J 2
(-6175 5925);
DISPLAY 0.872340 (-6175 5925);
DISPLAY INVISIBLE (-6175 5925);
FORCEPROP 1 LAST PATH I252
J 2
(-5848 6050);
DISPLAY 0.872340 (-5848 6050);
PAINT GREEN (-5848 6050);
DISPLAY INVISIBLE (-5848 6050);
FORCEADD TAP..1
R 2
(-5850 5950);
FORCEPROP 3 LASTPIN (-5800 5950) SIG_NAME M_G_CPU0_SA_DQS_DP<1>
J 0
(-5790 5960);
DISPLAY 0.659574 (-5790 5960);
PAINT MONO (-5790 5960);
DISPLAY INVISIBLE (-5790 5960);
FORCEPROP 1 LASTPIN (-5800 5950) BN 1
J 2
(-5788 5958);
DISPLAY 0.489362 (-5788 5958);
PAINT GREEN (-5788 5958);
FORCEPROP 2 LAST CDS_LIB mstr_standard
J 2
(-5850 5950);
DISPLAY 0.723404 (-5850 5950);
PAINT MONO (-5850 5950);
DISPLAY INVISIBLE (-5850 5950);
FORCEPROP 1 LAST BODY_TYPE PLUMBING
J 2
(-5850 6000);
DISPLAY 0.872340 (-5850 6000);
PAINT GREEN (-5850 6000);
DISPLAY INVISIBLE (-5850 6000);
FORCEPROP 1 LAST HDL_TAP TRUE
J 2
(-6175 5825);
DISPLAY 0.872340 (-6175 5825);
DISPLAY INVISIBLE (-6175 5825);
FORCEPROP 1 LAST PATH I253
J 2
(-5848 5950);
DISPLAY 0.872340 (-5848 5950);
PAINT GREEN (-5848 5950);
DISPLAY INVISIBLE (-5848 5950);
FORCEADD TAP..1
R 2
(-5850 5850);
FORCEPROP 3 LASTPIN (-5800 5850) SIG_NAME M_G_CPU0_SA_DQS_DP<2>
J 0
(-5790 5860);
DISPLAY 0.659574 (-5790 5860);
PAINT MONO (-5790 5860);
DISPLAY INVISIBLE (-5790 5860);
FORCEPROP 1 LASTPIN (-5800 5850) BN 2
J 2
(-5788 5858);
DISPLAY 0.489362 (-5788 5858);
PAINT GREEN (-5788 5858);
FORCEPROP 2 LAST CDS_LIB mstr_standard
J 2
(-5850 5850);
DISPLAY 0.723404 (-5850 5850);
PAINT MONO (-5850 5850);
DISPLAY INVISIBLE (-5850 5850);
FORCEPROP 1 LAST BODY_TYPE PLUMBING
J 2
(-5850 5900);
DISPLAY 0.872340 (-5850 5900);
PAINT GREEN (-5850 5900);
DISPLAY INVISIBLE (-5850 5900);
FORCEPROP 1 LAST HDL_TAP TRUE
J 2
(-6175 5725);
DISPLAY 0.872340 (-6175 5725);
DISPLAY INVISIBLE (-6175 5725);
FORCEPROP 1 LAST PATH I254
J 2
(-5848 5850);
DISPLAY 0.872340 (-5848 5850);
PAINT GREEN (-5848 5850);
DISPLAY INVISIBLE (-5848 5850);
FORCEADD TAP..1
R 2
(-5850 5750);
FORCEPROP 3 LASTPIN (-5800 5750) SIG_NAME M_G_CPU0_SA_DQS_DP<3>
J 0
(-5790 5760);
DISPLAY 0.659574 (-5790 5760);
PAINT MONO (-5790 5760);
DISPLAY INVISIBLE (-5790 5760);
FORCEPROP 1 LASTPIN (-5800 5750) BN 3
J 2
(-5788 5758);
DISPLAY 0.489362 (-5788 5758);
PAINT GREEN (-5788 5758);
FORCEPROP 2 LAST CDS_LIB mstr_standard
J 2
(-5850 5750);
DISPLAY 0.723404 (-5850 5750);
PAINT MONO (-5850 5750);
DISPLAY INVISIBLE (-5850 5750);
FORCEPROP 1 LAST BODY_TYPE PLUMBING
J 2
(-5850 5800);
DISPLAY 0.872340 (-5850 5800);
PAINT GREEN (-5850 5800);
DISPLAY INVISIBLE (-5850 5800);
FORCEPROP 1 LAST HDL_TAP TRUE
J 2
(-6175 5625);
DISPLAY 0.872340 (-6175 5625);
DISPLAY INVISIBLE (-6175 5625);
FORCEPROP 1 LAST PATH I255
J 2
(-5848 5750);
DISPLAY 0.872340 (-5848 5750);
PAINT GREEN (-5848 5750);
DISPLAY INVISIBLE (-5848 5750);
FORCEADD TAP..1
R 2
(-5850 5650);
FORCEPROP 3 LASTPIN (-5800 5650) SIG_NAME M_G_CPU0_SA_DQS_DP<4>
J 0
(-5790 5660);
DISPLAY 0.659574 (-5790 5660);
PAINT MONO (-5790 5660);
DISPLAY INVISIBLE (-5790 5660);
FORCEPROP 1 LASTPIN (-5800 5650) BN 4
J 2
(-5788 5658);
DISPLAY 0.489362 (-5788 5658);
PAINT GREEN (-5788 5658);
FORCEPROP 2 LAST CDS_LIB mstr_standard
J 2
(-5850 5650);
DISPLAY 0.723404 (-5850 5650);
PAINT MONO (-5850 5650);
DISPLAY INVISIBLE (-5850 5650);
FORCEPROP 1 LAST BODY_TYPE PLUMBING
J 2
(-5850 5700);
DISPLAY 0.872340 (-5850 5700);
PAINT GREEN (-5850 5700);
DISPLAY INVISIBLE (-5850 5700);
FORCEPROP 1 LAST HDL_TAP TRUE
J 2
(-6175 5525);
DISPLAY 0.872340 (-6175 5525);
DISPLAY INVISIBLE (-6175 5525);
FORCEPROP 1 LAST PATH I256
J 2
(-5848 5650);
DISPLAY 0.872340 (-5848 5650);
PAINT GREEN (-5848 5650);
DISPLAY INVISIBLE (-5848 5650);
FORCEADD TAP..1
R 2
(-6050 6000);
FORCEPROP 3 LASTPIN (-6000 6000) SIG_NAME M_G_CPU0_SA_DQS_DN<0>
J 0
(-5990 6010);
DISPLAY 0.659574 (-5990 6010);
PAINT MONO (-5990 6010);
DISPLAY INVISIBLE (-5990 6010);
FORCEPROP 1 LASTPIN (-6000 6000) BN 0
J 2
(-5988 6008);
DISPLAY 0.489362 (-5988 6008);
PAINT GREEN (-5988 6008);
FORCEPROP 2 LAST CDS_LIB mstr_standard
J 2
(-6050 6000);
DISPLAY 0.723404 (-6050 6000);
PAINT MONO (-6050 6000);
DISPLAY INVISIBLE (-6050 6000);
FORCEPROP 1 LAST BODY_TYPE PLUMBING
J 2
(-6050 6050);
DISPLAY 0.872340 (-6050 6050);
PAINT GREEN (-6050 6050);
DISPLAY INVISIBLE (-6050 6050);
FORCEPROP 1 LAST HDL_TAP TRUE
J 2
(-6375 5875);
DISPLAY 0.872340 (-6375 5875);
DISPLAY INVISIBLE (-6375 5875);
FORCEPROP 1 LAST PATH I257
J 2
(-6048 6000);
DISPLAY 0.872340 (-6048 6000);
PAINT GREEN (-6048 6000);
DISPLAY INVISIBLE (-6048 6000);
FORCEADD TAP..1
R 2
(-6050 5900);
FORCEPROP 3 LASTPIN (-6000 5900) SIG_NAME M_G_CPU0_SA_DQS_DN<1>
J 0
(-5990 5910);
DISPLAY 0.659574 (-5990 5910);
PAINT MONO (-5990 5910);
DISPLAY INVISIBLE (-5990 5910);
FORCEPROP 1 LASTPIN (-6000 5900) BN 1
J 2
(-5988 5908);
DISPLAY 0.489362 (-5988 5908);
PAINT GREEN (-5988 5908);
FORCEPROP 2 LAST CDS_LIB mstr_standard
J 2
(-6050 5900);
DISPLAY 0.723404 (-6050 5900);
PAINT MONO (-6050 5900);
DISPLAY INVISIBLE (-6050 5900);
FORCEPROP 1 LAST BODY_TYPE PLUMBING
J 2
(-6050 5950);
DISPLAY 0.872340 (-6050 5950);
PAINT GREEN (-6050 5950);
DISPLAY INVISIBLE (-6050 5950);
FORCEPROP 1 LAST HDL_TAP TRUE
J 2
(-6375 5775);
DISPLAY 0.872340 (-6375 5775);
DISPLAY INVISIBLE (-6375 5775);
FORCEPROP 1 LAST PATH I258
J 2
(-6048 5900);
DISPLAY 0.872340 (-6048 5900);
PAINT GREEN (-6048 5900);
DISPLAY INVISIBLE (-6048 5900);
FORCEADD TAP..1
R 2
(-6050 5800);
FORCEPROP 3 LASTPIN (-6000 5800) SIG_NAME M_G_CPU0_SA_DQS_DN<2>
J 0
(-5990 5810);
DISPLAY 0.659574 (-5990 5810);
PAINT MONO (-5990 5810);
DISPLAY INVISIBLE (-5990 5810);
FORCEPROP 1 LASTPIN (-6000 5800) BN 2
J 2
(-5988 5808);
DISPLAY 0.489362 (-5988 5808);
PAINT GREEN (-5988 5808);
FORCEPROP 2 LAST CDS_LIB mstr_standard
J 2
(-6050 5800);
DISPLAY 0.723404 (-6050 5800);
PAINT MONO (-6050 5800);
DISPLAY INVISIBLE (-6050 5800);
FORCEPROP 1 LAST BODY_TYPE PLUMBING
J 2
(-6050 5850);
DISPLAY 0.872340 (-6050 5850);
PAINT GREEN (-6050 5850);
DISPLAY INVISIBLE (-6050 5850);
FORCEPROP 1 LAST HDL_TAP TRUE
J 2
(-6375 5675);
DISPLAY 0.872340 (-6375 5675);
DISPLAY INVISIBLE (-6375 5675);
FORCEPROP 1 LAST PATH I259
J 2
(-6048 5800);
DISPLAY 0.872340 (-6048 5800);
PAINT GREEN (-6048 5800);
DISPLAY INVISIBLE (-6048 5800);
FORCEADD TAP..1
R 2
(-6050 5700);
FORCEPROP 3 LASTPIN (-6000 5700) SIG_NAME M_G_CPU0_SA_DQS_DN<3>
J 0
(-5990 5710);
DISPLAY 0.659574 (-5990 5710);
PAINT MONO (-5990 5710);
DISPLAY INVISIBLE (-5990 5710);
FORCEPROP 1 LASTPIN (-6000 5700) BN 3
J 2
(-5988 5708);
DISPLAY 0.489362 (-5988 5708);
PAINT GREEN (-5988 5708);
FORCEPROP 2 LAST CDS_LIB mstr_standard
J 2
(-6050 5700);
DISPLAY 0.723404 (-6050 5700);
PAINT MONO (-6050 5700);
DISPLAY INVISIBLE (-6050 5700);
FORCEPROP 1 LAST BODY_TYPE PLUMBING
J 2
(-6050 5750);
DISPLAY 0.872340 (-6050 5750);
PAINT GREEN (-6050 5750);
DISPLAY INVISIBLE (-6050 5750);
FORCEPROP 1 LAST HDL_TAP TRUE
J 2
(-6375 5575);
DISPLAY 0.872340 (-6375 5575);
DISPLAY INVISIBLE (-6375 5575);
FORCEPROP 1 LAST PATH I260
J 2
(-6048 5700);
DISPLAY 0.872340 (-6048 5700);
PAINT GREEN (-6048 5700);
DISPLAY INVISIBLE (-6048 5700);
FORCEADD TAP..1
R 2
(-5850 5450);
FORCEPROP 3 LASTPIN (-5800 5450) SIG_NAME M_G_CPU0_SA_DQS_DP<6>
J 0
(-5790 5460);
DISPLAY 0.659574 (-5790 5460);
PAINT MONO (-5790 5460);
DISPLAY INVISIBLE (-5790 5460);
FORCEPROP 1 LASTPIN (-5800 5450) BN 6
J 2
(-5788 5458);
DISPLAY 0.489362 (-5788 5458);
PAINT GREEN (-5788 5458);
FORCEPROP 2 LAST CDS_LIB mstr_standard
J 2
(-5850 5450);
DISPLAY 0.723404 (-5850 5450);
PAINT MONO (-5850 5450);
DISPLAY INVISIBLE (-5850 5450);
FORCEPROP 1 LAST BODY_TYPE PLUMBING
J 2
(-5850 5500);
DISPLAY 0.872340 (-5850 5500);
PAINT GREEN (-5850 5500);
DISPLAY INVISIBLE (-5850 5500);
FORCEPROP 1 LAST HDL_TAP TRUE
J 2
(-6175 5325);
DISPLAY 0.872340 (-6175 5325);
DISPLAY INVISIBLE (-6175 5325);
FORCEPROP 1 LAST PATH I261
J 2
(-5848 5450);
DISPLAY 0.872340 (-5848 5450);
PAINT GREEN (-5848 5450);
DISPLAY INVISIBLE (-5848 5450);
FORCEADD TAP..1
R 2
(-5850 5550);
FORCEPROP 3 LASTPIN (-5800 5550) SIG_NAME M_G_CPU0_SA_DQS_DP<5>
J 0
(-5790 5560);
DISPLAY 0.659574 (-5790 5560);
PAINT MONO (-5790 5560);
DISPLAY INVISIBLE (-5790 5560);
FORCEPROP 1 LASTPIN (-5800 5550) BN 5
J 2
(-5788 5558);
DISPLAY 0.489362 (-5788 5558);
PAINT GREEN (-5788 5558);
FORCEPROP 2 LAST CDS_LIB mstr_standard
J 2
(-5850 5550);
DISPLAY 0.723404 (-5850 5550);
PAINT MONO (-5850 5550);
DISPLAY INVISIBLE (-5850 5550);
FORCEPROP 1 LAST BODY_TYPE PLUMBING
J 2
(-5850 5600);
DISPLAY 0.872340 (-5850 5600);
PAINT GREEN (-5850 5600);
DISPLAY INVISIBLE (-5850 5600);
FORCEPROP 1 LAST HDL_TAP TRUE
J 2
(-6175 5425);
DISPLAY 0.872340 (-6175 5425);
DISPLAY INVISIBLE (-6175 5425);
FORCEPROP 1 LAST PATH I262
J 2
(-5848 5550);
DISPLAY 0.872340 (-5848 5550);
PAINT GREEN (-5848 5550);
DISPLAY INVISIBLE (-5848 5550);
FORCEADD TAP..1
R 2
(-5850 5350);
FORCEPROP 3 LASTPIN (-5800 5350) SIG_NAME M_G_CPU0_SA_DQS_DP<7>
J 0
(-5790 5360);
DISPLAY 0.659574 (-5790 5360);
PAINT MONO (-5790 5360);
DISPLAY INVISIBLE (-5790 5360);
FORCEPROP 1 LASTPIN (-5800 5350) BN 7
J 2
(-5788 5358);
DISPLAY 0.489362 (-5788 5358);
PAINT GREEN (-5788 5358);
FORCEPROP 2 LAST CDS_LIB mstr_standard
J 2
(-5850 5350);
DISPLAY 0.723404 (-5850 5350);
PAINT MONO (-5850 5350);
DISPLAY INVISIBLE (-5850 5350);
FORCEPROP 1 LAST BODY_TYPE PLUMBING
J 2
(-5850 5400);
DISPLAY 0.872340 (-5850 5400);
PAINT GREEN (-5850 5400);
DISPLAY INVISIBLE (-5850 5400);
FORCEPROP 1 LAST HDL_TAP TRUE
J 2
(-6175 5225);
DISPLAY 0.872340 (-6175 5225);
DISPLAY INVISIBLE (-6175 5225);
FORCEPROP 1 LAST PATH I263
J 2
(-5848 5350);
DISPLAY 0.872340 (-5848 5350);
PAINT GREEN (-5848 5350);
DISPLAY INVISIBLE (-5848 5350);
FORCEADD TAP..1
R 2
(-5850 5250);
FORCEPROP 3 LASTPIN (-5800 5250) SIG_NAME M_G_CPU0_SA_DQS_DP<8>
J 0
(-5790 5260);
DISPLAY 0.659574 (-5790 5260);
PAINT MONO (-5790 5260);
DISPLAY INVISIBLE (-5790 5260);
FORCEPROP 1 LASTPIN (-5800 5250) BN 8
J 2
(-5788 5258);
DISPLAY 0.489362 (-5788 5258);
PAINT GREEN (-5788 5258);
FORCEPROP 2 LAST CDS_LIB mstr_standard
J 2
(-5850 5250);
DISPLAY 0.723404 (-5850 5250);
PAINT MONO (-5850 5250);
DISPLAY INVISIBLE (-5850 5250);
FORCEPROP 1 LAST BODY_TYPE PLUMBING
J 2
(-5850 5300);
DISPLAY 0.872340 (-5850 5300);
PAINT GREEN (-5850 5300);
DISPLAY INVISIBLE (-5850 5300);
FORCEPROP 1 LAST HDL_TAP TRUE
J 2
(-6175 5125);
DISPLAY 0.872340 (-6175 5125);
DISPLAY INVISIBLE (-6175 5125);
FORCEPROP 1 LAST PATH I264
J 2
(-5848 5250);
DISPLAY 0.872340 (-5848 5250);
PAINT GREEN (-5848 5250);
DISPLAY INVISIBLE (-5848 5250);
FORCEADD TAP..1
R 2
(-5850 5150);
FORCEPROP 3 LASTPIN (-5800 5150) SIG_NAME M_G_CPU0_SA_DQS_DP<9>
J 0
(-5790 5160);
DISPLAY 0.659574 (-5790 5160);
PAINT MONO (-5790 5160);
DISPLAY INVISIBLE (-5790 5160);
FORCEPROP 1 LASTPIN (-5800 5150) BN 9
J 2
(-5788 5158);
DISPLAY 0.489362 (-5788 5158);
PAINT GREEN (-5788 5158);
FORCEPROP 2 LAST CDS_LIB mstr_standard
J 2
(-5850 5150);
DISPLAY 0.723404 (-5850 5150);
PAINT MONO (-5850 5150);
DISPLAY INVISIBLE (-5850 5150);
FORCEPROP 1 LAST BODY_TYPE PLUMBING
J 2
(-5850 5200);
DISPLAY 0.872340 (-5850 5200);
PAINT GREEN (-5850 5200);
DISPLAY INVISIBLE (-5850 5200);
FORCEPROP 1 LAST HDL_TAP TRUE
J 2
(-6175 5025);
DISPLAY 0.872340 (-6175 5025);
DISPLAY INVISIBLE (-6175 5025);
FORCEPROP 1 LAST PATH I265
J 2
(-5848 5150);
DISPLAY 0.872340 (-5848 5150);
PAINT GREEN (-5848 5150);
DISPLAY INVISIBLE (-5848 5150);
FORCEADD TAP..1
R 2
(-6050 5600);
FORCEPROP 3 LASTPIN (-6000 5600) SIG_NAME M_G_CPU0_SA_DQS_DN<4>
J 0
(-5990 5610);
DISPLAY 0.659574 (-5990 5610);
PAINT MONO (-5990 5610);
DISPLAY INVISIBLE (-5990 5610);
FORCEPROP 1 LASTPIN (-6000 5600) BN 4
J 2
(-5988 5608);
DISPLAY 0.489362 (-5988 5608);
PAINT GREEN (-5988 5608);
FORCEPROP 2 LAST CDS_LIB mstr_standard
J 2
(-6050 5600);
DISPLAY 0.723404 (-6050 5600);
PAINT MONO (-6050 5600);
DISPLAY INVISIBLE (-6050 5600);
FORCEPROP 1 LAST BODY_TYPE PLUMBING
J 2
(-6050 5650);
DISPLAY 0.872340 (-6050 5650);
PAINT GREEN (-6050 5650);
DISPLAY INVISIBLE (-6050 5650);
FORCEPROP 1 LAST HDL_TAP TRUE
J 2
(-6375 5475);
DISPLAY 0.872340 (-6375 5475);
DISPLAY INVISIBLE (-6375 5475);
FORCEPROP 1 LAST PATH I266
J 2
(-6048 5600);
DISPLAY 0.872340 (-6048 5600);
PAINT GREEN (-6048 5600);
DISPLAY INVISIBLE (-6048 5600);
FORCEADD TAP..1
R 2
(-6050 5500);
FORCEPROP 3 LASTPIN (-6000 5500) SIG_NAME M_G_CPU0_SA_DQS_DN<5>
J 0
(-5990 5510);
DISPLAY 0.659574 (-5990 5510);
PAINT MONO (-5990 5510);
DISPLAY INVISIBLE (-5990 5510);
FORCEPROP 1 LASTPIN (-6000 5500) BN 5
J 2
(-5988 5508);
DISPLAY 0.489362 (-5988 5508);
PAINT GREEN (-5988 5508);
FORCEPROP 2 LAST CDS_LIB mstr_standard
J 2
(-6050 5500);
DISPLAY 0.723404 (-6050 5500);
PAINT MONO (-6050 5500);
DISPLAY INVISIBLE (-6050 5500);
FORCEPROP 1 LAST BODY_TYPE PLUMBING
J 2
(-6050 5550);
DISPLAY 0.872340 (-6050 5550);
PAINT GREEN (-6050 5550);
DISPLAY INVISIBLE (-6050 5550);
FORCEPROP 1 LAST HDL_TAP TRUE
J 2
(-6375 5375);
DISPLAY 0.872340 (-6375 5375);
DISPLAY INVISIBLE (-6375 5375);
FORCEPROP 1 LAST PATH I267
J 2
(-6048 5500);
DISPLAY 0.872340 (-6048 5500);
PAINT GREEN (-6048 5500);
DISPLAY INVISIBLE (-6048 5500);
FORCEADD TAP..1
R 2
(-6050 5400);
FORCEPROP 3 LASTPIN (-6000 5400) SIG_NAME M_G_CPU0_SA_DQS_DN<6>
J 0
(-5990 5410);
DISPLAY 0.659574 (-5990 5410);
PAINT MONO (-5990 5410);
DISPLAY INVISIBLE (-5990 5410);
FORCEPROP 1 LASTPIN (-6000 5400) BN 6
J 2
(-5988 5408);
DISPLAY 0.489362 (-5988 5408);
PAINT GREEN (-5988 5408);
FORCEPROP 2 LAST CDS_LIB mstr_standard
J 2
(-6050 5400);
DISPLAY 0.723404 (-6050 5400);
PAINT MONO (-6050 5400);
DISPLAY INVISIBLE (-6050 5400);
FORCEPROP 1 LAST BODY_TYPE PLUMBING
J 2
(-6050 5450);
DISPLAY 0.872340 (-6050 5450);
PAINT GREEN (-6050 5450);
DISPLAY INVISIBLE (-6050 5450);
FORCEPROP 1 LAST HDL_TAP TRUE
J 2
(-6375 5275);
DISPLAY 0.872340 (-6375 5275);
DISPLAY INVISIBLE (-6375 5275);
FORCEPROP 1 LAST PATH I268
J 2
(-6048 5400);
DISPLAY 0.872340 (-6048 5400);
PAINT GREEN (-6048 5400);
DISPLAY INVISIBLE (-6048 5400);
FORCEADD TAP..1
R 2
(-6050 5300);
FORCEPROP 3 LASTPIN (-6000 5300) SIG_NAME M_G_CPU0_SA_DQS_DN<7>
J 0
(-5990 5310);
DISPLAY 0.659574 (-5990 5310);
PAINT MONO (-5990 5310);
DISPLAY INVISIBLE (-5990 5310);
FORCEPROP 1 LASTPIN (-6000 5300) BN 7
J 2
(-5988 5308);
DISPLAY 0.489362 (-5988 5308);
PAINT GREEN (-5988 5308);
FORCEPROP 2 LAST CDS_LIB mstr_standard
J 2
(-6050 5300);
DISPLAY 0.723404 (-6050 5300);
PAINT MONO (-6050 5300);
DISPLAY INVISIBLE (-6050 5300);
FORCEPROP 1 LAST BODY_TYPE PLUMBING
J 2
(-6050 5350);
DISPLAY 0.872340 (-6050 5350);
PAINT GREEN (-6050 5350);
DISPLAY INVISIBLE (-6050 5350);
FORCEPROP 1 LAST HDL_TAP TRUE
J 2
(-6375 5175);
DISPLAY 0.872340 (-6375 5175);
DISPLAY INVISIBLE (-6375 5175);
FORCEPROP 1 LAST PATH I269
J 2
(-6048 5300);
DISPLAY 0.872340 (-6048 5300);
PAINT GREEN (-6048 5300);
DISPLAY INVISIBLE (-6048 5300);
FORCEADD TAP..1
R 2
(-6050 5200);
FORCEPROP 3 LASTPIN (-6000 5200) SIG_NAME M_G_CPU0_SA_DQS_DN<8>
J 0
(-5990 5210);
DISPLAY 0.659574 (-5990 5210);
PAINT MONO (-5990 5210);
DISPLAY INVISIBLE (-5990 5210);
FORCEPROP 1 LASTPIN (-6000 5200) BN 8
J 2
(-5988 5208);
DISPLAY 0.489362 (-5988 5208);
PAINT GREEN (-5988 5208);
FORCEPROP 2 LAST CDS_LIB mstr_standard
J 2
(-6050 5200);
DISPLAY 0.723404 (-6050 5200);
PAINT MONO (-6050 5200);
DISPLAY INVISIBLE (-6050 5200);
FORCEPROP 1 LAST BODY_TYPE PLUMBING
J 2
(-6050 5250);
DISPLAY 0.872340 (-6050 5250);
PAINT GREEN (-6050 5250);
DISPLAY INVISIBLE (-6050 5250);
FORCEPROP 1 LAST HDL_TAP TRUE
J 2
(-6375 5075);
DISPLAY 0.872340 (-6375 5075);
DISPLAY INVISIBLE (-6375 5075);
FORCEPROP 1 LAST PATH I270
J 2
(-6048 5200);
DISPLAY 0.872340 (-6048 5200);
PAINT GREEN (-6048 5200);
DISPLAY INVISIBLE (-6048 5200);
FORCEADD TAP..1
R 2
(-5850 5000);
FORCEPROP 3 LASTPIN (-5800 5000) SIG_NAME M_G_CPU0_SB_DQS_DP<0>
J 0
(-5790 5010);
DISPLAY 0.659574 (-5790 5010);
PAINT MONO (-5790 5010);
DISPLAY INVISIBLE (-5790 5010);
FORCEPROP 1 LASTPIN (-5800 5000) BN 0
J 2
(-5788 5008);
DISPLAY 0.489362 (-5788 5008);
PAINT GREEN (-5788 5008);
FORCEPROP 2 LAST CDS_LIB mstr_standard
J 2
(-5850 5000);
DISPLAY 0.723404 (-5850 5000);
PAINT MONO (-5850 5000);
DISPLAY INVISIBLE (-5850 5000);
FORCEPROP 1 LAST BODY_TYPE PLUMBING
J 2
(-5850 5050);
DISPLAY 0.872340 (-5850 5050);
PAINT GREEN (-5850 5050);
DISPLAY INVISIBLE (-5850 5050);
FORCEPROP 1 LAST HDL_TAP TRUE
J 2
(-6175 4875);
DISPLAY 0.872340 (-6175 4875);
DISPLAY INVISIBLE (-6175 4875);
FORCEPROP 1 LAST PATH I271
J 2
(-5848 5000);
DISPLAY 0.872340 (-5848 5000);
PAINT GREEN (-5848 5000);
DISPLAY INVISIBLE (-5848 5000);
FORCEADD TAP..1
R 2
(-5850 4900);
FORCEPROP 3 LASTPIN (-5800 4900) SIG_NAME M_G_CPU0_SB_DQS_DP<1>
J 0
(-5790 4910);
DISPLAY 0.659574 (-5790 4910);
PAINT MONO (-5790 4910);
DISPLAY INVISIBLE (-5790 4910);
FORCEPROP 1 LASTPIN (-5800 4900) BN 1
J 2
(-5788 4908);
DISPLAY 0.489362 (-5788 4908);
PAINT GREEN (-5788 4908);
FORCEPROP 2 LAST CDS_LIB mstr_standard
J 2
(-5850 4900);
DISPLAY 0.723404 (-5850 4900);
PAINT MONO (-5850 4900);
DISPLAY INVISIBLE (-5850 4900);
FORCEPROP 1 LAST BODY_TYPE PLUMBING
J 2
(-5850 4950);
DISPLAY 0.872340 (-5850 4950);
PAINT GREEN (-5850 4950);
DISPLAY INVISIBLE (-5850 4950);
FORCEPROP 1 LAST HDL_TAP TRUE
J 2
(-6175 4775);
DISPLAY 0.872340 (-6175 4775);
DISPLAY INVISIBLE (-6175 4775);
FORCEPROP 1 LAST PATH I272
J 2
(-5848 4900);
DISPLAY 0.872340 (-5848 4900);
PAINT GREEN (-5848 4900);
DISPLAY INVISIBLE (-5848 4900);
FORCEADD TAP..1
R 2
(-5850 4800);
FORCEPROP 3 LASTPIN (-5800 4800) SIG_NAME M_G_CPU0_SB_DQS_DP<2>
J 0
(-5790 4810);
DISPLAY 0.659574 (-5790 4810);
PAINT MONO (-5790 4810);
DISPLAY INVISIBLE (-5790 4810);
FORCEPROP 1 LASTPIN (-5800 4800) BN 2
J 2
(-5788 4808);
DISPLAY 0.489362 (-5788 4808);
PAINT GREEN (-5788 4808);
FORCEPROP 2 LAST CDS_LIB mstr_standard
J 2
(-5850 4800);
DISPLAY 0.723404 (-5850 4800);
PAINT MONO (-5850 4800);
DISPLAY INVISIBLE (-5850 4800);
FORCEPROP 1 LAST BODY_TYPE PLUMBING
J 2
(-5850 4850);
DISPLAY 0.872340 (-5850 4850);
PAINT GREEN (-5850 4850);
DISPLAY INVISIBLE (-5850 4850);
FORCEPROP 1 LAST HDL_TAP TRUE
J 2
(-6175 4675);
DISPLAY 0.872340 (-6175 4675);
DISPLAY INVISIBLE (-6175 4675);
FORCEPROP 1 LAST PATH I273
J 2
(-5848 4800);
DISPLAY 0.872340 (-5848 4800);
PAINT GREEN (-5848 4800);
DISPLAY INVISIBLE (-5848 4800);
FORCEADD TAP..1
R 2
(-5850 4700);
FORCEPROP 3 LASTPIN (-5800 4700) SIG_NAME M_G_CPU0_SB_DQS_DP<3>
J 0
(-5790 4710);
DISPLAY 0.659574 (-5790 4710);
PAINT MONO (-5790 4710);
DISPLAY INVISIBLE (-5790 4710);
FORCEPROP 1 LASTPIN (-5800 4700) BN 3
J 2
(-5788 4708);
DISPLAY 0.489362 (-5788 4708);
PAINT GREEN (-5788 4708);
FORCEPROP 2 LAST CDS_LIB mstr_standard
J 2
(-5850 4700);
DISPLAY 0.723404 (-5850 4700);
PAINT MONO (-5850 4700);
DISPLAY INVISIBLE (-5850 4700);
FORCEPROP 1 LAST BODY_TYPE PLUMBING
J 2
(-5850 4750);
DISPLAY 0.872340 (-5850 4750);
PAINT GREEN (-5850 4750);
DISPLAY INVISIBLE (-5850 4750);
FORCEPROP 1 LAST HDL_TAP TRUE
J 2
(-6175 4575);
DISPLAY 0.872340 (-6175 4575);
DISPLAY INVISIBLE (-6175 4575);
FORCEPROP 1 LAST PATH I274
J 2
(-5848 4700);
DISPLAY 0.872340 (-5848 4700);
PAINT GREEN (-5848 4700);
DISPLAY INVISIBLE (-5848 4700);
FORCEADD TAP..1
R 2
(-6050 5100);
FORCEPROP 3 LASTPIN (-6000 5100) SIG_NAME M_G_CPU0_SA_DQS_DN<9>
J 0
(-5990 5110);
DISPLAY 0.659574 (-5990 5110);
PAINT MONO (-5990 5110);
DISPLAY INVISIBLE (-5990 5110);
FORCEPROP 1 LASTPIN (-6000 5100) BN 9
J 2
(-5988 5108);
DISPLAY 0.489362 (-5988 5108);
PAINT GREEN (-5988 5108);
FORCEPROP 2 LAST CDS_LIB mstr_standard
J 2
(-6050 5100);
DISPLAY 0.723404 (-6050 5100);
PAINT MONO (-6050 5100);
DISPLAY INVISIBLE (-6050 5100);
FORCEPROP 1 LAST BODY_TYPE PLUMBING
J 2
(-6050 5150);
DISPLAY 0.872340 (-6050 5150);
PAINT GREEN (-6050 5150);
DISPLAY INVISIBLE (-6050 5150);
FORCEPROP 1 LAST HDL_TAP TRUE
J 2
(-6375 4975);
DISPLAY 0.872340 (-6375 4975);
DISPLAY INVISIBLE (-6375 4975);
FORCEPROP 1 LAST PATH I275
J 2
(-6048 5100);
DISPLAY 0.872340 (-6048 5100);
PAINT GREEN (-6048 5100);
DISPLAY INVISIBLE (-6048 5100);
FORCEADD TAP..1
R 2
(-6050 4950);
FORCEPROP 3 LASTPIN (-6000 4950) SIG_NAME M_G_CPU0_SB_DQS_DN<0>
J 0
(-5990 4960);
DISPLAY 0.659574 (-5990 4960);
PAINT MONO (-5990 4960);
DISPLAY INVISIBLE (-5990 4960);
FORCEPROP 1 LASTPIN (-6000 4950) BN 0
J 2
(-5988 4958);
DISPLAY 0.489362 (-5988 4958);
PAINT GREEN (-5988 4958);
FORCEPROP 2 LAST CDS_LIB mstr_standard
J 2
(-6050 4950);
DISPLAY 0.723404 (-6050 4950);
PAINT MONO (-6050 4950);
DISPLAY INVISIBLE (-6050 4950);
FORCEPROP 1 LAST BODY_TYPE PLUMBING
J 2
(-6050 5000);
DISPLAY 0.872340 (-6050 5000);
PAINT GREEN (-6050 5000);
DISPLAY INVISIBLE (-6050 5000);
FORCEPROP 1 LAST HDL_TAP TRUE
J 2
(-6375 4825);
DISPLAY 0.872340 (-6375 4825);
DISPLAY INVISIBLE (-6375 4825);
FORCEPROP 1 LAST PATH I276
J 2
(-6048 4950);
DISPLAY 0.872340 (-6048 4950);
PAINT GREEN (-6048 4950);
DISPLAY INVISIBLE (-6048 4950);
FORCEADD TAP..1
R 2
(-6050 4850);
FORCEPROP 3 LASTPIN (-6000 4850) SIG_NAME M_G_CPU0_SB_DQS_DN<1>
J 0
(-5990 4860);
DISPLAY 0.659574 (-5990 4860);
PAINT MONO (-5990 4860);
DISPLAY INVISIBLE (-5990 4860);
FORCEPROP 1 LASTPIN (-6000 4850) BN 1
J 2
(-5988 4858);
DISPLAY 0.489362 (-5988 4858);
PAINT GREEN (-5988 4858);
FORCEPROP 2 LAST CDS_LIB mstr_standard
J 2
(-6050 4850);
DISPLAY 0.723404 (-6050 4850);
PAINT MONO (-6050 4850);
DISPLAY INVISIBLE (-6050 4850);
FORCEPROP 1 LAST BODY_TYPE PLUMBING
J 2
(-6050 4900);
DISPLAY 0.872340 (-6050 4900);
PAINT GREEN (-6050 4900);
DISPLAY INVISIBLE (-6050 4900);
FORCEPROP 1 LAST HDL_TAP TRUE
J 2
(-6375 4725);
DISPLAY 0.872340 (-6375 4725);
DISPLAY INVISIBLE (-6375 4725);
FORCEPROP 1 LAST PATH I277
J 2
(-6048 4850);
DISPLAY 0.872340 (-6048 4850);
PAINT GREEN (-6048 4850);
DISPLAY INVISIBLE (-6048 4850);
FORCEADD TAP..1
R 2
(-6050 4750);
FORCEPROP 3 LASTPIN (-6000 4750) SIG_NAME M_G_CPU0_SB_DQS_DN<2>
J 0
(-5990 4760);
DISPLAY 0.659574 (-5990 4760);
PAINT MONO (-5990 4760);
DISPLAY INVISIBLE (-5990 4760);
FORCEPROP 1 LASTPIN (-6000 4750) BN 2
J 2
(-5988 4758);
DISPLAY 0.489362 (-5988 4758);
PAINT GREEN (-5988 4758);
FORCEPROP 2 LAST CDS_LIB mstr_standard
J 2
(-6050 4750);
DISPLAY 0.723404 (-6050 4750);
PAINT MONO (-6050 4750);
DISPLAY INVISIBLE (-6050 4750);
FORCEPROP 1 LAST BODY_TYPE PLUMBING
J 2
(-6050 4800);
DISPLAY 0.872340 (-6050 4800);
PAINT GREEN (-6050 4800);
DISPLAY INVISIBLE (-6050 4800);
FORCEPROP 1 LAST HDL_TAP TRUE
J 2
(-6375 4625);
DISPLAY 0.872340 (-6375 4625);
DISPLAY INVISIBLE (-6375 4625);
FORCEPROP 1 LAST PATH I278
J 2
(-6048 4750);
DISPLAY 0.872340 (-6048 4750);
PAINT GREEN (-6048 4750);
DISPLAY INVISIBLE (-6048 4750);
FORCEADD TAP..1
R 2
(-6050 4650);
FORCEPROP 3 LASTPIN (-6000 4650) SIG_NAME M_G_CPU0_SB_DQS_DN<3>
J 0
(-5990 4660);
DISPLAY 0.659574 (-5990 4660);
PAINT MONO (-5990 4660);
DISPLAY INVISIBLE (-5990 4660);
FORCEPROP 1 LASTPIN (-6000 4650) BN 3
J 2
(-5988 4658);
DISPLAY 0.489362 (-5988 4658);
PAINT GREEN (-5988 4658);
FORCEPROP 2 LAST CDS_LIB mstr_standard
J 2
(-6050 4650);
DISPLAY 0.723404 (-6050 4650);
PAINT MONO (-6050 4650);
DISPLAY INVISIBLE (-6050 4650);
FORCEPROP 1 LAST BODY_TYPE PLUMBING
J 2
(-6050 4700);
DISPLAY 0.872340 (-6050 4700);
PAINT GREEN (-6050 4700);
DISPLAY INVISIBLE (-6050 4700);
FORCEPROP 1 LAST HDL_TAP TRUE
J 2
(-6375 4525);
DISPLAY 0.872340 (-6375 4525);
DISPLAY INVISIBLE (-6375 4525);
FORCEPROP 1 LAST PATH I279
J 2
(-6048 4650);
DISPLAY 0.872340 (-6048 4650);
PAINT GREEN (-6048 4650);
DISPLAY INVISIBLE (-6048 4650);
FORCEADD TAP..1
R 2
(-5850 4600);
FORCEPROP 3 LASTPIN (-5800 4600) SIG_NAME M_G_CPU0_SB_DQS_DP<4>
J 0
(-5790 4610);
DISPLAY 0.659574 (-5790 4610);
PAINT MONO (-5790 4610);
DISPLAY INVISIBLE (-5790 4610);
FORCEPROP 1 LASTPIN (-5800 4600) BN 4
J 2
(-5788 4608);
DISPLAY 0.489362 (-5788 4608);
PAINT GREEN (-5788 4608);
FORCEPROP 2 LAST CDS_LIB mstr_standard
J 2
(-5850 4600);
DISPLAY 0.723404 (-5850 4600);
PAINT MONO (-5850 4600);
DISPLAY INVISIBLE (-5850 4600);
FORCEPROP 1 LAST BODY_TYPE PLUMBING
J 2
(-5850 4650);
DISPLAY 0.872340 (-5850 4650);
PAINT GREEN (-5850 4650);
DISPLAY INVISIBLE (-5850 4650);
FORCEPROP 1 LAST HDL_TAP TRUE
J 2
(-6175 4475);
DISPLAY 0.872340 (-6175 4475);
DISPLAY INVISIBLE (-6175 4475);
FORCEPROP 1 LAST PATH I280
J 2
(-5848 4600);
DISPLAY 0.872340 (-5848 4600);
PAINT GREEN (-5848 4600);
DISPLAY INVISIBLE (-5848 4600);
FORCEADD TAP..1
R 2
(-5850 4400);
FORCEPROP 3 LASTPIN (-5800 4400) SIG_NAME M_G_CPU0_SB_DQS_DP<6>
J 0
(-5790 4410);
DISPLAY 0.659574 (-5790 4410);
PAINT MONO (-5790 4410);
DISPLAY INVISIBLE (-5790 4410);
FORCEPROP 1 LASTPIN (-5800 4400) BN 6
J 2
(-5788 4408);
DISPLAY 0.489362 (-5788 4408);
PAINT GREEN (-5788 4408);
FORCEPROP 2 LAST CDS_LIB mstr_standard
J 2
(-5850 4400);
DISPLAY 0.723404 (-5850 4400);
PAINT MONO (-5850 4400);
DISPLAY INVISIBLE (-5850 4400);
FORCEPROP 1 LAST BODY_TYPE PLUMBING
J 2
(-5850 4450);
DISPLAY 0.872340 (-5850 4450);
PAINT GREEN (-5850 4450);
DISPLAY INVISIBLE (-5850 4450);
FORCEPROP 1 LAST HDL_TAP TRUE
J 2
(-6175 4275);
DISPLAY 0.872340 (-6175 4275);
DISPLAY INVISIBLE (-6175 4275);
FORCEPROP 1 LAST PATH I281
J 2
(-5848 4400);
DISPLAY 0.872340 (-5848 4400);
PAINT GREEN (-5848 4400);
DISPLAY INVISIBLE (-5848 4400);
FORCEADD TAP..1
R 2
(-5850 4500);
FORCEPROP 3 LASTPIN (-5800 4500) SIG_NAME M_G_CPU0_SB_DQS_DP<5>
J 0
(-5790 4510);
DISPLAY 0.659574 (-5790 4510);
PAINT MONO (-5790 4510);
DISPLAY INVISIBLE (-5790 4510);
FORCEPROP 1 LASTPIN (-5800 4500) BN 5
J 2
(-5788 4508);
DISPLAY 0.489362 (-5788 4508);
PAINT GREEN (-5788 4508);
FORCEPROP 2 LAST CDS_LIB mstr_standard
J 2
(-5850 4500);
DISPLAY 0.723404 (-5850 4500);
PAINT MONO (-5850 4500);
DISPLAY INVISIBLE (-5850 4500);
FORCEPROP 1 LAST BODY_TYPE PLUMBING
J 2
(-5850 4550);
DISPLAY 0.872340 (-5850 4550);
PAINT GREEN (-5850 4550);
DISPLAY INVISIBLE (-5850 4550);
FORCEPROP 1 LAST HDL_TAP TRUE
J 2
(-6175 4375);
DISPLAY 0.872340 (-6175 4375);
DISPLAY INVISIBLE (-6175 4375);
FORCEPROP 1 LAST PATH I282
J 2
(-5848 4500);
DISPLAY 0.872340 (-5848 4500);
PAINT GREEN (-5848 4500);
DISPLAY INVISIBLE (-5848 4500);
FORCEADD TAP..1
R 2
(-5850 4300);
FORCEPROP 3 LASTPIN (-5800 4300) SIG_NAME M_G_CPU0_SB_DQS_DP<7>
J 0
(-5790 4310);
DISPLAY 0.659574 (-5790 4310);
PAINT MONO (-5790 4310);
DISPLAY INVISIBLE (-5790 4310);
FORCEPROP 1 LASTPIN (-5800 4300) BN 7
J 2
(-5788 4308);
DISPLAY 0.489362 (-5788 4308);
PAINT GREEN (-5788 4308);
FORCEPROP 2 LAST CDS_LIB mstr_standard
J 2
(-5850 4300);
DISPLAY 0.723404 (-5850 4300);
PAINT MONO (-5850 4300);
DISPLAY INVISIBLE (-5850 4300);
FORCEPROP 1 LAST BODY_TYPE PLUMBING
J 2
(-5850 4350);
DISPLAY 0.872340 (-5850 4350);
PAINT GREEN (-5850 4350);
DISPLAY INVISIBLE (-5850 4350);
FORCEPROP 1 LAST HDL_TAP TRUE
J 2
(-6175 4175);
DISPLAY 0.872340 (-6175 4175);
DISPLAY INVISIBLE (-6175 4175);
FORCEPROP 1 LAST PATH I283
J 2
(-5848 4300);
DISPLAY 0.872340 (-5848 4300);
PAINT GREEN (-5848 4300);
DISPLAY INVISIBLE (-5848 4300);
FORCEADD TAP..1
R 2
(-5850 4200);
FORCEPROP 3 LASTPIN (-5800 4200) SIG_NAME M_G_CPU0_SB_DQS_DP<8>
J 0
(-5790 4210);
DISPLAY 0.659574 (-5790 4210);
PAINT MONO (-5790 4210);
DISPLAY INVISIBLE (-5790 4210);
FORCEPROP 1 LASTPIN (-5800 4200) BN 8
J 2
(-5788 4208);
DISPLAY 0.489362 (-5788 4208);
PAINT GREEN (-5788 4208);
FORCEPROP 2 LAST CDS_LIB mstr_standard
J 2
(-5850 4200);
DISPLAY 0.723404 (-5850 4200);
PAINT MONO (-5850 4200);
DISPLAY INVISIBLE (-5850 4200);
FORCEPROP 1 LAST BODY_TYPE PLUMBING
J 2
(-5850 4250);
DISPLAY 0.872340 (-5850 4250);
PAINT GREEN (-5850 4250);
DISPLAY INVISIBLE (-5850 4250);
FORCEPROP 1 LAST HDL_TAP TRUE
J 2
(-6175 4075);
DISPLAY 0.872340 (-6175 4075);
DISPLAY INVISIBLE (-6175 4075);
FORCEPROP 1 LAST PATH I284
J 2
(-5848 4200);
DISPLAY 0.872340 (-5848 4200);
PAINT GREEN (-5848 4200);
DISPLAY INVISIBLE (-5848 4200);
FORCEADD TAP..1
R 2
(-5850 4100);
FORCEPROP 3 LASTPIN (-5800 4100) SIG_NAME M_G_CPU0_SB_DQS_DP<9>
J 0
(-5790 4110);
DISPLAY 0.659574 (-5790 4110);
PAINT MONO (-5790 4110);
DISPLAY INVISIBLE (-5790 4110);
FORCEPROP 1 LASTPIN (-5800 4100) BN 9
J 2
(-5788 4108);
DISPLAY 0.489362 (-5788 4108);
PAINT GREEN (-5788 4108);
FORCEPROP 2 LAST CDS_LIB mstr_standard
J 2
(-5850 4100);
DISPLAY 0.723404 (-5850 4100);
PAINT MONO (-5850 4100);
DISPLAY INVISIBLE (-5850 4100);
FORCEPROP 1 LAST BODY_TYPE PLUMBING
J 2
(-5850 4150);
DISPLAY 0.872340 (-5850 4150);
PAINT GREEN (-5850 4150);
DISPLAY INVISIBLE (-5850 4150);
FORCEPROP 1 LAST HDL_TAP TRUE
J 2
(-6175 3975);
DISPLAY 0.872340 (-6175 3975);
DISPLAY INVISIBLE (-6175 3975);
FORCEPROP 1 LAST PATH I285
J 2
(-5848 4100);
DISPLAY 0.872340 (-5848 4100);
PAINT GREEN (-5848 4100);
DISPLAY INVISIBLE (-5848 4100);
FORCEADD TAP..1
R 2
(-6050 4550);
FORCEPROP 3 LASTPIN (-6000 4550) SIG_NAME M_G_CPU0_SB_DQS_DN<4>
J 0
(-5990 4560);
DISPLAY 0.659574 (-5990 4560);
PAINT MONO (-5990 4560);
DISPLAY INVISIBLE (-5990 4560);
FORCEPROP 1 LASTPIN (-6000 4550) BN 4
J 2
(-5988 4558);
DISPLAY 0.489362 (-5988 4558);
PAINT GREEN (-5988 4558);
FORCEPROP 2 LAST CDS_LIB mstr_standard
J 2
(-6050 4550);
DISPLAY 0.723404 (-6050 4550);
PAINT MONO (-6050 4550);
DISPLAY INVISIBLE (-6050 4550);
FORCEPROP 1 LAST BODY_TYPE PLUMBING
J 2
(-6050 4600);
DISPLAY 0.872340 (-6050 4600);
PAINT GREEN (-6050 4600);
DISPLAY INVISIBLE (-6050 4600);
FORCEPROP 1 LAST HDL_TAP TRUE
J 2
(-6375 4425);
DISPLAY 0.872340 (-6375 4425);
DISPLAY INVISIBLE (-6375 4425);
FORCEPROP 1 LAST PATH I286
J 2
(-6048 4550);
DISPLAY 0.872340 (-6048 4550);
PAINT GREEN (-6048 4550);
DISPLAY INVISIBLE (-6048 4550);
FORCEADD TAP..1
R 2
(-6050 4450);
FORCEPROP 3 LASTPIN (-6000 4450) SIG_NAME M_G_CPU0_SB_DQS_DN<5>
J 0
(-5990 4460);
DISPLAY 0.659574 (-5990 4460);
PAINT MONO (-5990 4460);
DISPLAY INVISIBLE (-5990 4460);
FORCEPROP 1 LASTPIN (-6000 4450) BN 5
J 2
(-5988 4458);
DISPLAY 0.489362 (-5988 4458);
PAINT GREEN (-5988 4458);
FORCEPROP 2 LAST CDS_LIB mstr_standard
J 2
(-6050 4450);
DISPLAY 0.723404 (-6050 4450);
PAINT MONO (-6050 4450);
DISPLAY INVISIBLE (-6050 4450);
FORCEPROP 1 LAST BODY_TYPE PLUMBING
J 2
(-6050 4500);
DISPLAY 0.872340 (-6050 4500);
PAINT GREEN (-6050 4500);
DISPLAY INVISIBLE (-6050 4500);
FORCEPROP 1 LAST HDL_TAP TRUE
J 2
(-6375 4325);
DISPLAY 0.872340 (-6375 4325);
DISPLAY INVISIBLE (-6375 4325);
FORCEPROP 1 LAST PATH I287
J 2
(-6048 4450);
DISPLAY 0.872340 (-6048 4450);
PAINT GREEN (-6048 4450);
DISPLAY INVISIBLE (-6048 4450);
FORCEADD TAP..1
R 2
(-6050 4250);
FORCEPROP 3 LASTPIN (-6000 4250) SIG_NAME M_G_CPU0_SB_DQS_DN<7>
J 0
(-5990 4260);
DISPLAY 0.659574 (-5990 4260);
PAINT MONO (-5990 4260);
DISPLAY INVISIBLE (-5990 4260);
FORCEPROP 1 LASTPIN (-6000 4250) BN 7
J 2
(-5988 4258);
DISPLAY 0.489362 (-5988 4258);
PAINT GREEN (-5988 4258);
FORCEPROP 2 LAST CDS_LIB mstr_standard
J 2
(-6050 4250);
DISPLAY 0.723404 (-6050 4250);
PAINT MONO (-6050 4250);
DISPLAY INVISIBLE (-6050 4250);
FORCEPROP 1 LAST BODY_TYPE PLUMBING
J 2
(-6050 4300);
DISPLAY 0.872340 (-6050 4300);
PAINT GREEN (-6050 4300);
DISPLAY INVISIBLE (-6050 4300);
FORCEPROP 1 LAST HDL_TAP TRUE
J 2
(-6375 4125);
DISPLAY 0.872340 (-6375 4125);
DISPLAY INVISIBLE (-6375 4125);
FORCEPROP 1 LAST PATH I288
J 2
(-6048 4250);
DISPLAY 0.872340 (-6048 4250);
PAINT GREEN (-6048 4250);
DISPLAY INVISIBLE (-6048 4250);
FORCEADD TAP..1
R 2
(-6050 4350);
FORCEPROP 3 LASTPIN (-6000 4350) SIG_NAME M_G_CPU0_SB_DQS_DN<6>
J 0
(-5990 4360);
DISPLAY 0.659574 (-5990 4360);
PAINT MONO (-5990 4360);
DISPLAY INVISIBLE (-5990 4360);
FORCEPROP 1 LASTPIN (-6000 4350) BN 6
J 2
(-5988 4358);
DISPLAY 0.489362 (-5988 4358);
PAINT GREEN (-5988 4358);
FORCEPROP 2 LAST CDS_LIB mstr_standard
J 2
(-6050 4350);
DISPLAY 0.723404 (-6050 4350);
PAINT MONO (-6050 4350);
DISPLAY INVISIBLE (-6050 4350);
FORCEPROP 1 LAST BODY_TYPE PLUMBING
J 2
(-6050 4400);
DISPLAY 0.872340 (-6050 4400);
PAINT GREEN (-6050 4400);
DISPLAY INVISIBLE (-6050 4400);
FORCEPROP 1 LAST HDL_TAP TRUE
J 2
(-6375 4225);
DISPLAY 0.872340 (-6375 4225);
DISPLAY INVISIBLE (-6375 4225);
FORCEPROP 1 LAST PATH I289
J 2
(-6048 4350);
DISPLAY 0.872340 (-6048 4350);
PAINT GREEN (-6048 4350);
DISPLAY INVISIBLE (-6048 4350);
FORCEADD TAP..1
R 2
(-6050 4150);
FORCEPROP 3 LASTPIN (-6000 4150) SIG_NAME M_G_CPU0_SB_DQS_DN<8>
J 0
(-5990 4160);
DISPLAY 0.659574 (-5990 4160);
PAINT MONO (-5990 4160);
DISPLAY INVISIBLE (-5990 4160);
FORCEPROP 1 LASTPIN (-6000 4150) BN 8
J 2
(-5988 4158);
DISPLAY 0.489362 (-5988 4158);
PAINT GREEN (-5988 4158);
FORCEPROP 2 LAST CDS_LIB mstr_standard
J 2
(-6050 4150);
DISPLAY 0.723404 (-6050 4150);
PAINT MONO (-6050 4150);
DISPLAY INVISIBLE (-6050 4150);
FORCEPROP 1 LAST BODY_TYPE PLUMBING
J 2
(-6050 4200);
DISPLAY 0.872340 (-6050 4200);
PAINT GREEN (-6050 4200);
DISPLAY INVISIBLE (-6050 4200);
FORCEPROP 1 LAST HDL_TAP TRUE
J 2
(-6375 4025);
DISPLAY 0.872340 (-6375 4025);
DISPLAY INVISIBLE (-6375 4025);
FORCEPROP 1 LAST PATH I290
J 2
(-6048 4150);
DISPLAY 0.872340 (-6048 4150);
PAINT GREEN (-6048 4150);
DISPLAY INVISIBLE (-6048 4150);
FORCEADD OFFPAGE..3
R 2
(-6750 6075);
FORCEPROP 2 LAST $XR0 92 
J 0
(-6999 6075);
DISPLAY 0.638298 (-6999 6075);
PAINT MONO (-6999 6075);
FORCEPROP 2 LAST CDS_LIB standard
J 0
(-6750 6075);
DISPLAY INVISIBLE (-6750 6075);
FORCEPROP 1 LAST OFFPAGE TRUE
J 2
(-7075 5950);
DISPLAY 0.872340 (-7075 5950);
PAINT GREEN (-7075 5950);
DISPLAY INVISIBLE (-7075 5950);
FORCEPROP 1 LAST COMMENT_BODY TRUE
J 2
(-6700 5975);
DISPLAY 0.872340 (-6700 5975);
PAINT GREEN (-6700 5975);
DISPLAY INVISIBLE (-6700 5975);
FORCEPROP 2 LAST PATH I291
J 0
(-7025 6125);
DISPLAY 1.021277 (-7025 6125);
DISPLAY INVISIBLE (-7025 6125);
FORCEADD OFFPAGE..3
R 2
(-6750 6025);
FORCEPROP 2 LAST $XR0 92 
J 0
(-6999 6025);
DISPLAY 0.638298 (-6999 6025);
PAINT MONO (-6999 6025);
FORCEPROP 2 LAST CDS_LIB standard
J 0
(-6750 6025);
DISPLAY INVISIBLE (-6750 6025);
FORCEPROP 1 LAST OFFPAGE TRUE
J 2
(-7075 5900);
DISPLAY 0.872340 (-7075 5900);
PAINT GREEN (-7075 5900);
DISPLAY INVISIBLE (-7075 5900);
FORCEPROP 1 LAST COMMENT_BODY TRUE
J 2
(-6700 5925);
DISPLAY 0.872340 (-6700 5925);
PAINT GREEN (-6700 5925);
DISPLAY INVISIBLE (-6700 5925);
FORCEPROP 2 LAST PATH I292
J 0
(-7025 6075);
DISPLAY 1.021277 (-7025 6075);
DISPLAY INVISIBLE (-7025 6075);
FORCEADD OFFPAGE..3
R 2
(-6750 5025);
FORCEPROP 2 LAST $XR0 92 
J 0
(-6999 5025);
DISPLAY 0.638298 (-6999 5025);
PAINT MONO (-6999 5025);
FORCEPROP 2 LAST CDS_LIB standard
J 0
(-6750 5025);
DISPLAY INVISIBLE (-6750 5025);
FORCEPROP 1 LAST OFFPAGE TRUE
J 2
(-7075 4900);
DISPLAY 0.872340 (-7075 4900);
PAINT GREEN (-7075 4900);
DISPLAY INVISIBLE (-7075 4900);
FORCEPROP 1 LAST COMMENT_BODY TRUE
J 2
(-6700 4925);
DISPLAY 0.872340 (-6700 4925);
PAINT GREEN (-6700 4925);
DISPLAY INVISIBLE (-6700 4925);
FORCEPROP 2 LAST PATH I293
J 0
(-7025 5075);
DISPLAY 1.021277 (-7025 5075);
DISPLAY INVISIBLE (-7025 5075);
FORCEADD OFFPAGE..3
R 2
(-6750 4975);
FORCEPROP 2 LAST $XR0 92 
J 0
(-6999 4975);
DISPLAY 0.638298 (-6999 4975);
PAINT MONO (-6999 4975);
FORCEPROP 2 LAST CDS_LIB standard
J 0
(-6750 4975);
DISPLAY INVISIBLE (-6750 4975);
FORCEPROP 1 LAST OFFPAGE TRUE
J 2
(-7075 4850);
DISPLAY 0.872340 (-7075 4850);
PAINT GREEN (-7075 4850);
DISPLAY INVISIBLE (-7075 4850);
FORCEPROP 1 LAST COMMENT_BODY TRUE
J 2
(-6700 4875);
DISPLAY 0.872340 (-6700 4875);
PAINT GREEN (-6700 4875);
DISPLAY INVISIBLE (-6700 4875);
FORCEPROP 2 LAST PATH I294
J 0
(-7025 5025);
DISPLAY 1.021277 (-7025 5025);
DISPLAY INVISIBLE (-7025 5025);
FORCEADD TAP..1
R 2
(-6050 4050);
FORCEPROP 3 LASTPIN (-6000 4050) SIG_NAME M_G_CPU0_SB_DQS_DN<9>
J 0
(-5990 4060);
DISPLAY 0.659574 (-5990 4060);
PAINT MONO (-5990 4060);
DISPLAY INVISIBLE (-5990 4060);
FORCEPROP 1 LASTPIN (-6000 4050) BN 9
J 2
(-5988 4058);
DISPLAY 0.489362 (-5988 4058);
PAINT GREEN (-5988 4058);
FORCEPROP 2 LAST CDS_LIB mstr_standard
J 2
(-6050 4050);
DISPLAY 0.723404 (-6050 4050);
PAINT MONO (-6050 4050);
DISPLAY INVISIBLE (-6050 4050);
FORCEPROP 1 LAST BODY_TYPE PLUMBING
J 2
(-6050 4100);
DISPLAY 0.872340 (-6050 4100);
PAINT GREEN (-6050 4100);
DISPLAY INVISIBLE (-6050 4100);
FORCEPROP 1 LAST HDL_TAP TRUE
J 2
(-6375 3925);
DISPLAY 0.872340 (-6375 3925);
DISPLAY INVISIBLE (-6375 3925);
FORCEPROP 1 LAST PATH I295
J 2
(-6048 4050);
DISPLAY 0.872340 (-6048 4050);
PAINT GREEN (-6048 4050);
DISPLAY INVISIBLE (-6048 4050);
FORCEADD TAP..1
R 2
(-6050 3900);
FORCEPROP 3 LASTPIN (-6000 3900) SIG_NAME M_G_CPU0_SA_CA<0>
J 0
(-5990 3910);
DISPLAY 0.659574 (-5990 3910);
PAINT MONO (-5990 3910);
DISPLAY INVISIBLE (-5990 3910);
FORCEPROP 1 LASTPIN (-6000 3900) BN 0
J 2
(-5988 3908);
DISPLAY 0.489362 (-5988 3908);
PAINT GREEN (-5988 3908);
FORCEPROP 2 LAST CDS_LIB mstr_standard
J 0
(-6050 3900);
DISPLAY 0.723404 (-6050 3900);
PAINT MONO (-6050 3900);
DISPLAY INVISIBLE (-6050 3900);
FORCEPROP 1 LAST BODY_TYPE PLUMBING
J 2
(-6050 3950);
DISPLAY 0.872340 (-6050 3950);
PAINT GREEN (-6050 3950);
DISPLAY INVISIBLE (-6050 3950);
FORCEPROP 1 LAST HDL_TAP TRUE
J 2
(-6375 3775);
DISPLAY 0.872340 (-6375 3775);
DISPLAY INVISIBLE (-6375 3775);
FORCEPROP 1 LAST PATH I296
J 2
(-6048 3900);
DISPLAY 0.872340 (-6048 3900);
PAINT GREEN (-6048 3900);
DISPLAY INVISIBLE (-6048 3900);
FORCEADD TAP..1
R 2
(-6050 3850);
FORCEPROP 3 LASTPIN (-6000 3850) SIG_NAME M_G_CPU0_SA_CA<1>
J 0
(-5990 3860);
DISPLAY 0.659574 (-5990 3860);
PAINT MONO (-5990 3860);
DISPLAY INVISIBLE (-5990 3860);
FORCEPROP 1 LASTPIN (-6000 3850) BN 1
J 2
(-5988 3858);
DISPLAY 0.489362 (-5988 3858);
PAINT GREEN (-5988 3858);
FORCEPROP 2 LAST CDS_LIB mstr_standard
J 0
(-6050 3850);
DISPLAY 0.723404 (-6050 3850);
PAINT MONO (-6050 3850);
DISPLAY INVISIBLE (-6050 3850);
FORCEPROP 1 LAST BODY_TYPE PLUMBING
J 2
(-6050 3900);
DISPLAY 0.872340 (-6050 3900);
PAINT GREEN (-6050 3900);
DISPLAY INVISIBLE (-6050 3900);
FORCEPROP 1 LAST HDL_TAP TRUE
J 2
(-6375 3725);
DISPLAY 0.872340 (-6375 3725);
DISPLAY INVISIBLE (-6375 3725);
FORCEPROP 1 LAST PATH I297
J 2
(-6048 3850);
DISPLAY 0.872340 (-6048 3850);
PAINT GREEN (-6048 3850);
DISPLAY INVISIBLE (-6048 3850);
FORCEADD TAP..1
R 2
(-6050 3800);
FORCEPROP 3 LASTPIN (-6000 3800) SIG_NAME M_G_CPU0_SA_CA<2>
J 0
(-5990 3810);
DISPLAY 0.659574 (-5990 3810);
PAINT MONO (-5990 3810);
DISPLAY INVISIBLE (-5990 3810);
FORCEPROP 1 LASTPIN (-6000 3800) BN 2
J 2
(-5988 3808);
DISPLAY 0.489362 (-5988 3808);
PAINT GREEN (-5988 3808);
FORCEPROP 2 LAST CDS_LIB mstr_standard
J 0
(-6050 3800);
DISPLAY 0.723404 (-6050 3800);
PAINT MONO (-6050 3800);
DISPLAY INVISIBLE (-6050 3800);
FORCEPROP 1 LAST BODY_TYPE PLUMBING
J 2
(-6050 3850);
DISPLAY 0.872340 (-6050 3850);
PAINT GREEN (-6050 3850);
DISPLAY INVISIBLE (-6050 3850);
FORCEPROP 1 LAST HDL_TAP TRUE
J 2
(-6375 3675);
DISPLAY 0.872340 (-6375 3675);
DISPLAY INVISIBLE (-6375 3675);
FORCEPROP 1 LAST PATH I298
J 2
(-6048 3800);
DISPLAY 0.872340 (-6048 3800);
PAINT GREEN (-6048 3800);
DISPLAY INVISIBLE (-6048 3800);
FORCEADD TAP..1
R 2
(-6050 3750);
FORCEPROP 3 LASTPIN (-6000 3750) SIG_NAME M_G_CPU0_SA_CA<3>
J 0
(-5990 3760);
DISPLAY 0.659574 (-5990 3760);
PAINT MONO (-5990 3760);
DISPLAY INVISIBLE (-5990 3760);
FORCEPROP 1 LASTPIN (-6000 3750) BN 3
J 2
(-5988 3758);
DISPLAY 0.489362 (-5988 3758);
PAINT GREEN (-5988 3758);
FORCEPROP 2 LAST CDS_LIB mstr_standard
J 0
(-6050 3750);
DISPLAY 0.723404 (-6050 3750);
PAINT MONO (-6050 3750);
DISPLAY INVISIBLE (-6050 3750);
FORCEPROP 1 LAST BODY_TYPE PLUMBING
J 2
(-6050 3800);
DISPLAY 0.872340 (-6050 3800);
PAINT GREEN (-6050 3800);
DISPLAY INVISIBLE (-6050 3800);
FORCEPROP 1 LAST HDL_TAP TRUE
J 2
(-6375 3625);
DISPLAY 0.872340 (-6375 3625);
DISPLAY INVISIBLE (-6375 3625);
FORCEPROP 1 LAST PATH I299
J 2
(-6048 3750);
DISPLAY 0.872340 (-6048 3750);
PAINT GREEN (-6048 3750);
DISPLAY INVISIBLE (-6048 3750);
FORCEADD TAP..1
R 2
(-6050 3700);
FORCEPROP 3 LASTPIN (-6000 3700) SIG_NAME M_G_CPU0_SA_CA<4>
J 0
(-5990 3710);
DISPLAY 0.659574 (-5990 3710);
PAINT MONO (-5990 3710);
DISPLAY INVISIBLE (-5990 3710);
FORCEPROP 1 LASTPIN (-6000 3700) BN 4
J 2
(-5988 3708);
DISPLAY 0.489362 (-5988 3708);
PAINT GREEN (-5988 3708);
FORCEPROP 2 LAST CDS_LIB mstr_standard
J 0
(-6050 3700);
DISPLAY 0.723404 (-6050 3700);
PAINT MONO (-6050 3700);
DISPLAY INVISIBLE (-6050 3700);
FORCEPROP 1 LAST BODY_TYPE PLUMBING
J 2
(-6050 3750);
DISPLAY 0.872340 (-6050 3750);
PAINT GREEN (-6050 3750);
DISPLAY INVISIBLE (-6050 3750);
FORCEPROP 1 LAST HDL_TAP TRUE
J 2
(-6375 3575);
DISPLAY 0.872340 (-6375 3575);
DISPLAY INVISIBLE (-6375 3575);
FORCEPROP 1 LAST PATH I300
J 2
(-6048 3700);
DISPLAY 0.872340 (-6048 3700);
PAINT GREEN (-6048 3700);
DISPLAY INVISIBLE (-6048 3700);
FORCEADD TAP..1
R 2
(-6050 3650);
FORCEPROP 3 LASTPIN (-6000 3650) SIG_NAME M_G_CPU0_SA_CA<5>
J 0
(-5990 3660);
DISPLAY 0.659574 (-5990 3660);
PAINT MONO (-5990 3660);
DISPLAY INVISIBLE (-5990 3660);
FORCEPROP 1 LASTPIN (-6000 3650) BN 5
J 2
(-5988 3658);
DISPLAY 0.489362 (-5988 3658);
PAINT GREEN (-5988 3658);
FORCEPROP 2 LAST CDS_LIB mstr_standard
J 0
(-6050 3650);
DISPLAY 0.723404 (-6050 3650);
PAINT MONO (-6050 3650);
DISPLAY INVISIBLE (-6050 3650);
FORCEPROP 1 LAST BODY_TYPE PLUMBING
J 2
(-6050 3700);
DISPLAY 0.872340 (-6050 3700);
PAINT GREEN (-6050 3700);
DISPLAY INVISIBLE (-6050 3700);
FORCEPROP 1 LAST HDL_TAP TRUE
J 2
(-6375 3525);
DISPLAY 0.872340 (-6375 3525);
DISPLAY INVISIBLE (-6375 3525);
FORCEPROP 1 LAST PATH I301
J 2
(-6048 3650);
DISPLAY 0.872340 (-6048 3650);
PAINT GREEN (-6048 3650);
DISPLAY INVISIBLE (-6048 3650);
FORCEADD TAP..1
R 2
(-6050 3600);
FORCEPROP 3 LASTPIN (-6000 3600) SIG_NAME M_G_CPU0_SA_CA<6>
J 0
(-5990 3610);
DISPLAY 0.659574 (-5990 3610);
PAINT MONO (-5990 3610);
DISPLAY INVISIBLE (-5990 3610);
FORCEPROP 1 LASTPIN (-6000 3600) BN 6
J 2
(-5988 3608);
DISPLAY 0.489362 (-5988 3608);
PAINT GREEN (-5988 3608);
FORCEPROP 2 LAST CDS_LIB mstr_standard
J 0
(-6050 3600);
DISPLAY 0.723404 (-6050 3600);
PAINT MONO (-6050 3600);
DISPLAY INVISIBLE (-6050 3600);
FORCEPROP 1 LAST BODY_TYPE PLUMBING
J 2
(-6050 3650);
DISPLAY 0.872340 (-6050 3650);
PAINT GREEN (-6050 3650);
DISPLAY INVISIBLE (-6050 3650);
FORCEPROP 1 LAST HDL_TAP TRUE
J 2
(-6375 3475);
DISPLAY 0.872340 (-6375 3475);
DISPLAY INVISIBLE (-6375 3475);
FORCEPROP 1 LAST PATH I302
J 2
(-6048 3600);
DISPLAY 0.872340 (-6048 3600);
PAINT GREEN (-6048 3600);
DISPLAY INVISIBLE (-6048 3600);
FORCEADD TAP..1
R 2
(-6050 3500);
FORCEPROP 3 LASTPIN (-6000 3500) SIG_NAME M_G_CPU0_SB_CA<0>
J 0
(-5990 3510);
DISPLAY 0.659574 (-5990 3510);
PAINT MONO (-5990 3510);
DISPLAY INVISIBLE (-5990 3510);
FORCEPROP 1 LASTPIN (-6000 3500) BN 0
J 2
(-5988 3508);
DISPLAY 0.489362 (-5988 3508);
PAINT GREEN (-5988 3508);
FORCEPROP 2 LAST CDS_LIB mstr_standard
J 0
(-6050 3500);
DISPLAY 0.723404 (-6050 3500);
PAINT MONO (-6050 3500);
DISPLAY INVISIBLE (-6050 3500);
FORCEPROP 1 LAST BODY_TYPE PLUMBING
J 2
(-6050 3550);
DISPLAY 0.872340 (-6050 3550);
PAINT GREEN (-6050 3550);
DISPLAY INVISIBLE (-6050 3550);
FORCEPROP 1 LAST HDL_TAP TRUE
J 2
(-6375 3375);
DISPLAY 0.872340 (-6375 3375);
DISPLAY INVISIBLE (-6375 3375);
FORCEPROP 1 LAST PATH I303
J 2
(-6048 3500);
DISPLAY 0.872340 (-6048 3500);
PAINT GREEN (-6048 3500);
DISPLAY INVISIBLE (-6048 3500);
FORCEADD TAP..1
R 2
(-6050 3450);
FORCEPROP 3 LASTPIN (-6000 3450) SIG_NAME M_G_CPU0_SB_CA<1>
J 0
(-5990 3460);
DISPLAY 0.659574 (-5990 3460);
PAINT MONO (-5990 3460);
DISPLAY INVISIBLE (-5990 3460);
FORCEPROP 1 LASTPIN (-6000 3450) BN 1
J 2
(-5988 3458);
DISPLAY 0.489362 (-5988 3458);
PAINT GREEN (-5988 3458);
FORCEPROP 2 LAST CDS_LIB mstr_standard
J 0
(-6050 3450);
DISPLAY 0.723404 (-6050 3450);
PAINT MONO (-6050 3450);
DISPLAY INVISIBLE (-6050 3450);
FORCEPROP 1 LAST BODY_TYPE PLUMBING
J 2
(-6050 3500);
DISPLAY 0.872340 (-6050 3500);
PAINT GREEN (-6050 3500);
DISPLAY INVISIBLE (-6050 3500);
FORCEPROP 1 LAST HDL_TAP TRUE
J 2
(-6375 3325);
DISPLAY 0.872340 (-6375 3325);
DISPLAY INVISIBLE (-6375 3325);
FORCEPROP 1 LAST PATH I304
J 2
(-6048 3450);
DISPLAY 0.872340 (-6048 3450);
PAINT GREEN (-6048 3450);
DISPLAY INVISIBLE (-6048 3450);
FORCEADD TAP..1
R 2
(-6050 3400);
FORCEPROP 3 LASTPIN (-6000 3400) SIG_NAME M_G_CPU0_SB_CA<2>
J 0
(-5990 3410);
DISPLAY 0.659574 (-5990 3410);
PAINT MONO (-5990 3410);
DISPLAY INVISIBLE (-5990 3410);
FORCEPROP 1 LASTPIN (-6000 3400) BN 2
J 2
(-5988 3408);
DISPLAY 0.489362 (-5988 3408);
PAINT GREEN (-5988 3408);
FORCEPROP 2 LAST CDS_LIB mstr_standard
J 0
(-6050 3400);
DISPLAY 0.723404 (-6050 3400);
PAINT MONO (-6050 3400);
DISPLAY INVISIBLE (-6050 3400);
FORCEPROP 1 LAST BODY_TYPE PLUMBING
J 2
(-6050 3450);
DISPLAY 0.872340 (-6050 3450);
PAINT GREEN (-6050 3450);
DISPLAY INVISIBLE (-6050 3450);
FORCEPROP 1 LAST HDL_TAP TRUE
J 2
(-6375 3275);
DISPLAY 0.872340 (-6375 3275);
DISPLAY INVISIBLE (-6375 3275);
FORCEPROP 1 LAST PATH I305
J 2
(-6048 3400);
DISPLAY 0.872340 (-6048 3400);
PAINT GREEN (-6048 3400);
DISPLAY INVISIBLE (-6048 3400);
FORCEADD TAP..1
R 2
(-6050 3350);
FORCEPROP 3 LASTPIN (-6000 3350) SIG_NAME M_G_CPU0_SB_CA<3>
J 0
(-5990 3360);
DISPLAY 0.659574 (-5990 3360);
PAINT MONO (-5990 3360);
DISPLAY INVISIBLE (-5990 3360);
FORCEPROP 1 LASTPIN (-6000 3350) BN 3
J 2
(-5988 3358);
DISPLAY 0.489362 (-5988 3358);
PAINT GREEN (-5988 3358);
FORCEPROP 2 LAST CDS_LIB mstr_standard
J 0
(-6050 3350);
DISPLAY 0.723404 (-6050 3350);
PAINT MONO (-6050 3350);
DISPLAY INVISIBLE (-6050 3350);
FORCEPROP 1 LAST BODY_TYPE PLUMBING
J 2
(-6050 3400);
DISPLAY 0.872340 (-6050 3400);
PAINT GREEN (-6050 3400);
DISPLAY INVISIBLE (-6050 3400);
FORCEPROP 1 LAST HDL_TAP TRUE
J 2
(-6375 3225);
DISPLAY 0.872340 (-6375 3225);
DISPLAY INVISIBLE (-6375 3225);
FORCEPROP 1 LAST PATH I306
J 2
(-6048 3350);
DISPLAY 0.872340 (-6048 3350);
PAINT GREEN (-6048 3350);
DISPLAY INVISIBLE (-6048 3350);
FORCEADD TAP..1
R 2
(-6050 3300);
FORCEPROP 3 LASTPIN (-6000 3300) SIG_NAME M_G_CPU0_SB_CA<4>
J 0
(-5990 3310);
DISPLAY 0.659574 (-5990 3310);
PAINT MONO (-5990 3310);
DISPLAY INVISIBLE (-5990 3310);
FORCEPROP 1 LASTPIN (-6000 3300) BN 4
J 2
(-5988 3308);
DISPLAY 0.489362 (-5988 3308);
PAINT GREEN (-5988 3308);
FORCEPROP 2 LAST CDS_LIB mstr_standard
J 0
(-6050 3300);
DISPLAY 0.723404 (-6050 3300);
PAINT MONO (-6050 3300);
DISPLAY INVISIBLE (-6050 3300);
FORCEPROP 1 LAST BODY_TYPE PLUMBING
J 2
(-6050 3350);
DISPLAY 0.872340 (-6050 3350);
PAINT GREEN (-6050 3350);
DISPLAY INVISIBLE (-6050 3350);
FORCEPROP 1 LAST HDL_TAP TRUE
J 2
(-6375 3175);
DISPLAY 0.872340 (-6375 3175);
DISPLAY INVISIBLE (-6375 3175);
FORCEPROP 1 LAST PATH I307
J 2
(-6048 3300);
DISPLAY 0.872340 (-6048 3300);
PAINT GREEN (-6048 3300);
DISPLAY INVISIBLE (-6048 3300);
FORCEADD TAP..1
R 2
(-6050 3250);
FORCEPROP 3 LASTPIN (-6000 3250) SIG_NAME M_G_CPU0_SB_CA<5>
J 0
(-5990 3260);
DISPLAY 0.659574 (-5990 3260);
PAINT MONO (-5990 3260);
DISPLAY INVISIBLE (-5990 3260);
FORCEPROP 1 LASTPIN (-6000 3250) BN 5
J 2
(-5988 3258);
DISPLAY 0.489362 (-5988 3258);
PAINT GREEN (-5988 3258);
FORCEPROP 2 LAST CDS_LIB mstr_standard
J 0
(-6050 3250);
DISPLAY 0.723404 (-6050 3250);
PAINT MONO (-6050 3250);
DISPLAY INVISIBLE (-6050 3250);
FORCEPROP 1 LAST BODY_TYPE PLUMBING
J 2
(-6050 3300);
DISPLAY 0.872340 (-6050 3300);
PAINT GREEN (-6050 3300);
DISPLAY INVISIBLE (-6050 3300);
FORCEPROP 1 LAST HDL_TAP TRUE
J 2
(-6375 3125);
DISPLAY 0.872340 (-6375 3125);
DISPLAY INVISIBLE (-6375 3125);
FORCEPROP 1 LAST PATH I308
J 2
(-6048 3250);
DISPLAY 0.872340 (-6048 3250);
PAINT GREEN (-6048 3250);
DISPLAY INVISIBLE (-6048 3250);
FORCEADD TAP..1
R 2
(-6050 3200);
FORCEPROP 3 LASTPIN (-6000 3200) SIG_NAME M_G_CPU0_SB_CA<6>
J 0
(-5990 3210);
DISPLAY 0.659574 (-5990 3210);
PAINT MONO (-5990 3210);
DISPLAY INVISIBLE (-5990 3210);
FORCEPROP 1 LASTPIN (-6000 3200) BN 6
J 2
(-5988 3208);
DISPLAY 0.489362 (-5988 3208);
PAINT GREEN (-5988 3208);
FORCEPROP 2 LAST CDS_LIB mstr_standard
J 0
(-6050 3200);
DISPLAY 0.723404 (-6050 3200);
PAINT MONO (-6050 3200);
DISPLAY INVISIBLE (-6050 3200);
FORCEPROP 1 LAST BODY_TYPE PLUMBING
J 2
(-6050 3250);
DISPLAY 0.872340 (-6050 3250);
PAINT GREEN (-6050 3250);
DISPLAY INVISIBLE (-6050 3250);
FORCEPROP 1 LAST HDL_TAP TRUE
J 2
(-6375 3075);
DISPLAY 0.872340 (-6375 3075);
DISPLAY INVISIBLE (-6375 3075);
FORCEPROP 1 LAST PATH I309
J 2
(-6048 3200);
DISPLAY 0.872340 (-6048 3200);
PAINT GREEN (-6048 3200);
DISPLAY INVISIBLE (-6048 3200);
FORCEADD OFFPAGE..2
R 2
(-6650 3925);
FORCEPROP 2 LAST $XR0 92 
J 0
(-6874 3925);
DISPLAY 0.638298 (-6874 3925);
PAINT MONO (-6874 3925);
FORCEPROP 2 LAST CDS_LIB standard
J 0
(-6650 3925);
DISPLAY INVISIBLE (-6650 3925);
FORCEPROP 1 LAST OFFPAGE TRUE
J 2
(-6975 3800);
DISPLAY 0.872340 (-6975 3800);
PAINT GREEN (-6975 3800);
DISPLAY INVISIBLE (-6975 3800);
FORCEPROP 1 LAST COMMENT_BODY TRUE
J 2
(-6605 3830);
DISPLAY 0.872340 (-6605 3830);
PAINT GREEN (-6605 3830);
DISPLAY INVISIBLE (-6605 3830);
FORCEPROP 2 LAST PATH I310
J 0
(-6900 3975);
DISPLAY 1.021277 (-6900 3975);
DISPLAY INVISIBLE (-6900 3975);
FORCEADD OFFPAGE..2
R 2
(-6650 3525);
FORCEPROP 2 LAST $XR0 92 
J 0
(-6874 3525);
DISPLAY 0.638298 (-6874 3525);
PAINT MONO (-6874 3525);
FORCEPROP 2 LAST CDS_LIB standard
J 0
(-6650 3525);
DISPLAY INVISIBLE (-6650 3525);
FORCEPROP 1 LAST OFFPAGE TRUE
J 2
(-6975 3400);
DISPLAY 0.872340 (-6975 3400);
PAINT GREEN (-6975 3400);
DISPLAY INVISIBLE (-6975 3400);
FORCEPROP 1 LAST COMMENT_BODY TRUE
J 2
(-6605 3430);
DISPLAY 0.872340 (-6605 3430);
PAINT GREEN (-6605 3430);
DISPLAY INVISIBLE (-6605 3430);
FORCEPROP 2 LAST PATH I311
J 0
(-6900 3575);
DISPLAY 1.021277 (-6900 3575);
DISPLAY INVISIBLE (-6900 3575);
FORCEADD OFFPAGE..2
R 2
(-6650 3000);
FORCEPROP 2 LAST $XR0 92 
J 0
(-6874 3000);
DISPLAY 0.638298 (-6874 3000);
PAINT MONO (-6874 3000);
FORCEPROP 2 LAST CDS_LIB standard
J 0
(-6650 3000);
DISPLAY INVISIBLE (-6650 3000);
FORCEPROP 1 LAST OFFPAGE TRUE
J 2
(-6975 2875);
DISPLAY 0.872340 (-6975 2875);
PAINT GREEN (-6975 2875);
DISPLAY INVISIBLE (-6975 2875);
FORCEPROP 1 LAST COMMENT_BODY TRUE
J 2
(-6605 2905);
DISPLAY 0.872340 (-6605 2905);
PAINT GREEN (-6605 2905);
DISPLAY INVISIBLE (-6605 2905);
FORCEPROP 2 LAST PATH I312
J 0
(-6900 3050);
DISPLAY 1.021277 (-6900 3050);
DISPLAY INVISIBLE (-6900 3050);
FORCEADD OFFPAGE..2
R 2
(-6650 3050);
FORCEPROP 2 LAST $XR0 92 
J 0
(-6874 3050);
DISPLAY 0.638298 (-6874 3050);
PAINT MONO (-6874 3050);
FORCEPROP 2 LAST CDS_LIB standard
J 0
(-6650 3050);
DISPLAY INVISIBLE (-6650 3050);
FORCEPROP 1 LAST OFFPAGE TRUE
J 2
(-6975 2925);
DISPLAY 0.872340 (-6975 2925);
PAINT GREEN (-6975 2925);
DISPLAY INVISIBLE (-6975 2925);
FORCEPROP 1 LAST COMMENT_BODY TRUE
J 2
(-6605 2955);
DISPLAY 0.872340 (-6605 2955);
PAINT GREEN (-6605 2955);
DISPLAY INVISIBLE (-6605 2955);
FORCEPROP 2 LAST PATH I313
J 0
(-6900 3100);
DISPLAY 1.021277 (-6900 3100);
DISPLAY INVISIBLE (-6900 3100);
FORCEADD OFFPAGE..2
R 2
(-6650 2850);
FORCEPROP 2 LAST $XR0 92 
J 0
(-6874 2850);
DISPLAY 0.638298 (-6874 2850);
PAINT MONO (-6874 2850);
FORCEPROP 2 LAST CDS_LIB standard
J 0
(-6650 2850);
DISPLAY INVISIBLE (-6650 2850);
FORCEPROP 1 LAST OFFPAGE TRUE
J 2
(-6975 2725);
DISPLAY 0.872340 (-6975 2725);
PAINT GREEN (-6975 2725);
DISPLAY INVISIBLE (-6975 2725);
FORCEPROP 1 LAST COMMENT_BODY TRUE
J 2
(-6605 2755);
DISPLAY 0.872340 (-6605 2755);
PAINT GREEN (-6605 2755);
DISPLAY INVISIBLE (-6605 2755);
FORCEPROP 2 LAST PATH I314
J 0
(-6900 2900);
DISPLAY 1.021277 (-6900 2900);
DISPLAY INVISIBLE (-6900 2900);
FORCEADD OFFPAGE..2
R 2
(-6650 2900);
FORCEPROP 2 LAST $XR0 92 
J 0
(-6874 2900);
DISPLAY 0.638298 (-6874 2900);
PAINT MONO (-6874 2900);
FORCEPROP 2 LAST CDS_LIB standard
J 0
(-6650 2900);
DISPLAY INVISIBLE (-6650 2900);
FORCEPROP 1 LAST OFFPAGE TRUE
J 2
(-6975 2775);
DISPLAY 0.872340 (-6975 2775);
PAINT GREEN (-6975 2775);
DISPLAY INVISIBLE (-6975 2775);
FORCEPROP 1 LAST COMMENT_BODY TRUE
J 2
(-6605 2805);
DISPLAY 0.872340 (-6605 2805);
PAINT GREEN (-6605 2805);
DISPLAY INVISIBLE (-6605 2805);
FORCEPROP 2 LAST PATH I315
J 0
(-6900 2950);
DISPLAY 1.021277 (-6900 2950);
DISPLAY INVISIBLE (-6900 2950);
FORCEADD OFFPAGE..5
(-6650 2650);
FORCEPROP 2 LAST $XR0 92 
J 0
(-6874 2650);
DISPLAY 0.638298 (-6874 2650);
PAINT MONO (-6874 2650);
FORCEPROP 2 LAST CDS_LIB mstr_standard
J 0
(-6650 2650);
DISPLAY INVISIBLE (-6650 2650);
FORCEPROP 1 LAST OFFPAGE TRUE
J 0
(-6325 2525);
DISPLAY 0.872340 (-6325 2525);
PAINT GREEN (-6325 2525);
DISPLAY INVISIBLE (-6325 2525);
FORCEPROP 1 LAST COMMENT_BODY TRUE
J 0
(-6550 2575);
DISPLAY 0.872340 (-6550 2575);
PAINT GREEN (-6550 2575);
DISPLAY INVISIBLE (-6550 2575);
FORCEPROP 2 LAST PATH I316
J 0
(-6900 2700);
DISPLAY 1.021277 (-6900 2700);
DISPLAY INVISIBLE (-6900 2700);
FORCEADD OFFPAGE..1
(-6650 2750);
FORCEPROP 2 LAST $XR0 92 
J 0
(-6901 2750);
DISPLAY 0.638298 (-6901 2750);
PAINT MONO (-6901 2750);
FORCEPROP 2 LAST CDS_LIB standard
J 0
(-6650 2750);
DISPLAY INVISIBLE (-6650 2750);
FORCEPROP 1 LAST OFFPAGE TRUE
J 0
(-6325 2625);
DISPLAY 0.872340 (-6325 2625);
PAINT GREEN (-6325 2625);
DISPLAY INVISIBLE (-6325 2625);
FORCEPROP 1 LAST COMMENT_BODY TRUE
J 0
(-6525 2650);
DISPLAY 0.872340 (-6525 2650);
PAINT GREEN (-6525 2650);
DISPLAY INVISIBLE (-6525 2650);
FORCEPROP 2 LAST PATH I317
J 0
(-6925 2800);
DISPLAY 1.021277 (-6925 2800);
DISPLAY INVISIBLE (-6925 2800);
FORCEADD OFFPAGE..1
(-6650 2400);
FORCEPROP 2 LAST $XR0 92 
J 0
(-6901 2400);
DISPLAY 0.638298 (-6901 2400);
PAINT MONO (-6901 2400);
FORCEPROP 2 LAST CDS_LIB standard
J 0
(-6650 2400);
DISPLAY INVISIBLE (-6650 2400);
FORCEPROP 1 LAST OFFPAGE TRUE
J 0
(-6325 2275);
DISPLAY 0.872340 (-6325 2275);
PAINT GREEN (-6325 2275);
DISPLAY INVISIBLE (-6325 2275);
FORCEPROP 1 LAST COMMENT_BODY TRUE
J 0
(-6525 2300);
DISPLAY 0.872340 (-6525 2300);
PAINT GREEN (-6525 2300);
DISPLAY INVISIBLE (-6525 2300);
FORCEPROP 2 LAST PATH I318
J 0
(-6925 2450);
DISPLAY 1.021277 (-6925 2450);
DISPLAY INVISIBLE (-6925 2450);
FORCEADD OFFPAGE..2
R 2
(-6650 2550);
FORCEPROP 2 LAST $XR0 92 
J 0
(-6874 2550);
DISPLAY 0.638298 (-6874 2550);
PAINT MONO (-6874 2550);
FORCEPROP 2 LAST CDS_LIB standard
J 0
(-6650 2550);
DISPLAY INVISIBLE (-6650 2550);
FORCEPROP 1 LAST OFFPAGE TRUE
J 2
(-6975 2425);
DISPLAY 0.872340 (-6975 2425);
PAINT GREEN (-6975 2425);
DISPLAY INVISIBLE (-6975 2425);
FORCEPROP 1 LAST COMMENT_BODY TRUE
J 2
(-6605 2455);
DISPLAY 0.872340 (-6605 2455);
PAINT GREEN (-6605 2455);
DISPLAY INVISIBLE (-6605 2455);
FORCEPROP 2 LAST PATH I319
J 0
(-6900 2600);
DISPLAY 1.021277 (-6900 2600);
DISPLAY INVISIBLE (-6900 2600);
FORCEADD OFFPAGE..2
R 2
(-6650 2500);
FORCEPROP 2 LAST $XR0 92 
J 0
(-6874 2500);
DISPLAY 0.638298 (-6874 2500);
PAINT MONO (-6874 2500);
FORCEPROP 2 LAST CDS_LIB standard
J 0
(-6650 2500);
DISPLAY INVISIBLE (-6650 2500);
FORCEPROP 1 LAST OFFPAGE TRUE
J 2
(-6975 2375);
DISPLAY 0.872340 (-6975 2375);
PAINT GREEN (-6975 2375);
DISPLAY INVISIBLE (-6975 2375);
FORCEPROP 1 LAST COMMENT_BODY TRUE
J 2
(-6605 2405);
DISPLAY 0.872340 (-6605 2405);
PAINT GREEN (-6605 2405);
DISPLAY INVISIBLE (-6605 2405);
FORCEPROP 2 LAST PATH I320
J 0
(-6900 2550);
DISPLAY 1.021277 (-6900 2550);
DISPLAY INVISIBLE (-6900 2550);
FORCEADD OFFPAGE..5
(-6650 2300);
FORCEPROP 2 LAST $XR0 92 
J 0
(-6874 2300);
DISPLAY 0.638298 (-6874 2300);
PAINT MONO (-6874 2300);
FORCEPROP 2 LAST CDS_LIB standard
J 0
(-6650 2300);
DISPLAY INVISIBLE (-6650 2300);
FORCEPROP 1 LAST OFFPAGE TRUE
J 0
(-6325 2175);
DISPLAY 0.872340 (-6325 2175);
PAINT GREEN (-6325 2175);
DISPLAY INVISIBLE (-6325 2175);
FORCEPROP 1 LAST COMMENT_BODY TRUE
J 0
(-6550 2225);
DISPLAY 0.872340 (-6550 2225);
PAINT GREEN (-6550 2225);
DISPLAY INVISIBLE (-6550 2225);
FORCEPROP 2 LAST PATH I321
J 0
(-6900 2350);
DISPLAY 1.021277 (-6900 2350);
DISPLAY INVISIBLE (-6900 2350);
FORCEADD OFFPAGE..5
(-6650 2100);
FORCEPROP 2 LAST $XR0 92 
J 0
(-6874 2100);
DISPLAY 0.638298 (-6874 2100);
PAINT MONO (-6874 2100);
FORCEPROP 2 LAST CDS_LIB standard
J 0
(-6650 2100);
DISPLAY INVISIBLE (-6650 2100);
FORCEPROP 1 LAST OFFPAGE TRUE
J 0
(-6325 1975);
DISPLAY 0.872340 (-6325 1975);
PAINT GREEN (-6325 1975);
DISPLAY INVISIBLE (-6325 1975);
FORCEPROP 1 LAST COMMENT_BODY TRUE
J 0
(-6550 2025);
DISPLAY 0.872340 (-6550 2025);
PAINT GREEN (-6550 2025);
DISPLAY INVISIBLE (-6550 2025);
FORCEPROP 2 LAST PATH I322
J 0
(-6900 2150);
DISPLAY 1.021277 (-6900 2150);
DISPLAY INVISIBLE (-6900 2150);
FORCEADD Q_RES..1
(-6975 2200);
FORCEPROP 1 LAST LOCATION R381
J 0
(-7300 2200);
DISPLAY 0.489362 (-7300 2200);
PAINT SKYBLUE (-7300 2200);
FORCEPROP 0 LAST $SEC 1
J 0
(-7150 2250);
DISPLAY 0.680851 (-7150 2250);
PAINT MONO (-7150 2250);
DISPLAY INVISIBLE (-7150 2250);
FORCEPROP 0 LAST CDS_SEC 1
J 0
(-7150 2250);
DISPLAY 1.021277 (-7150 2250);
DISPLAY INVISIBLE (-7150 2250);
FORCEPROP 1 LASTPIN (-7075 2200) $PN 1
J 0
(-7063 2212);
DISPLAY 0.489362 (-7063 2212);
PAINT MONO (-7063 2212);
FORCEPROP 1 LASTPIN (-6875 2200) $PN 2
J 0
(-6913 2212);
DISPLAY 0.489362 (-6913 2212);
PAINT MONO (-6913 2212);
FORCEPROP 1 LAST PACK_TYPE 0402LF
J 0
(-7300 2175);
DISPLAY 0.489362 (-7300 2175);
PAINT SKYBLUE (-7300 2175);
FORCEPROP 1 LAST TOLERANCE 1%
J 0
(-6700 2200);
DISPLAY 0.489362 (-6700 2200);
PAINT SKYBLUE (-6700 2200);
FORCEPROP 1 LAST VALUE 15
J 2
(-6650 2200);
DISPLAY 0.489362 (-6650 2200);
PAINT SKYBLUE (-6650 2200);
FORCEPROP 1 LAST MATERIAL CHIP
J 0
(-7100 2325);
DISPLAY 0.638298 (-7100 2325);
PAINT SKYBLUE (-7100 2325);
DISPLAY INVISIBLE (-7100 2325);
FORCEPROP 1 LAST WATTAGE 1/16W
J 2
(-6750 2325);
DISPLAY 0.638298 (-6750 2325);
PAINT SKYBLUE (-6750 2325);
DISPLAY INVISIBLE (-6750 2325);
FORCEPROP 2 LAST CDS_LIB pure_quanta
J 0
(-6975 2200);
DISPLAY INVISIBLE (-6975 2200);
FORCEPROP 1 LAST PATH I323
J 0
(-7025 2350);
DISPLAY 0.978723 (-7025 2350);
PAINT WHITE (-7025 2350);
DISPLAY INVISIBLE (-7025 2350);
FORCEPROP 1 LAST PART_NUMBER CS01502FB03
J 0
(-6875 2175);
DISPLAY 0.489362 (-6875 2175);
PAINT SKYBLUE (-6875 2175);
DISPLAY INVISIBLE (-6875 2175);
FORCEADD OFFPAGE..1
(-7850 2200);
FORCEPROP 2 LAST $XR0 92 
J 0
(-8071 2200);
DISPLAY 0.638298 (-8071 2200);
PAINT MONO (-8071 2200);
FORCEPROP 2 LAST CDS_LIB mstr_standard
J 0
(-7850 2200);
DISPLAY INVISIBLE (-7850 2200);
FORCEPROP 1 LAST OFFPAGE TRUE
J 0
(-7525 2075);
DISPLAY 0.872340 (-7525 2075);
PAINT GREEN (-7525 2075);
DISPLAY INVISIBLE (-7525 2075);
FORCEPROP 1 LAST COMMENT_BODY TRUE
J 0
(-7725 2100);
DISPLAY 0.872340 (-7725 2100);
PAINT GREEN (-7725 2100);
DISPLAY INVISIBLE (-7725 2100);
FORCEPROP 2 LAST PATH I324
J 0
(-8100 2250);
DISPLAY 1.021277 (-8100 2250);
DISPLAY INVISIBLE (-8100 2250);
FORCEADD CAD_NOTE..1
(-7850 2500);
FORCEPROP 0 LAST L1 R1955 PLACE CLOSE TO CPU < 25MM
J 0
(-8000 2375);
DISPLAY 0.617021 (-8000 2375);
PAINT WHITE (-8000 2375);
FORCEPROP 2 LAST CDS_LIB pure_quanta_power
J 0
(-7850 2500);
DISPLAY INVISIBLE (-7850 2500);
FORCEPROP 1 LAST COMMENT_BODY TRUE
J 0
(-7825 2600);
DISPLAY 0.574468 (-7825 2600);
PAINT WHITE (-7825 2600);
DISPLAY INVISIBLE (-7825 2600);
FORCEADD QUANTA_TITLE_BLOCK_C..1
(-100 100);
FORCEPROP 0 LAST CDS_CON_LAST_MODIFIED Thu Sep 14 16:11:50 2023
J 0
(-1985 115);
DISPLAY INVISIBLE (-1985 115);
FORCEPROP 1 LAST CUSTOM_TXT_CDS <CON_LAST_MODIFIED>
J 0
(-1985 115);
DISPLAY 0.978723 (-1985 115);
FORCEPROP 2 LAST CUSTOM_TXT_CDS <XR_PAGE_TITLE>
J 0
(-7990 5350);
DISPLAY 0.638298 (-7990 5350);
PAINT PINK (-7990 5350);
DISPLAY INVISIBLE (-7990 5350);
FORCEPROP 1 LAST CUSTOM_TXT_CDS <NAME_2>
J 0
(-3275 150);
FORCEPROP 1 LAST CUSTOM_TXT_CDS <NAME_1>
J 0
(-3275 275);
FORCEPROP 1 LAST CUSTOM_TXT_CDS <Q_NUMBER>
J 0
(-1503 203);
DISPLAY 1.212766 (-1503 203);
FORCEPROP 1 LAST CUSTOM_TXT_CDS <Q_PROJ>
J 0
(-2482 202);
DISPLAY 1.212766 (-2482 202);
FORCEPROP 1 LAST CUSTOM_TXT_CDS <Q_REV>
J 0
(-284 203);
DISPLAY 1.212766 (-284 203);
FORCEPROP 1 LAST CUSTOM_TXT_CDS <CON_PAGE_NUM> OF <CON_TOTAL_PAGES>
J 0
(-546 118);
DISPLAY 0.978723 (-546 118);
FORCEPROP 1 LAST Q_TITLE CPU0 DDR CHG
J 0
(-9375 150);
DISPLAY 2.446809 (-9375 150);
PAINT GREEN (-9375 150);
FORCEPROP 1 LAST CDS_LMAN_SYM_OUTLINE -9475,6775,100,-125
J 0
(-100 100);
DISPLAY 0.468085 (-100 100);
PAINT GREEN (-100 100);
DISPLAY INVISIBLE (-100 100);
FORCEPROP 2 LAST CDS_LIB pure_quanta
J 0
(-100 100);
DISPLAY INVISIBLE (-100 100);
FORCEPROP 2 LAST PAGE_BORDER TRUE
J 0
(-7990 5350);
DISPLAY 0.638298 (-7990 5350);
PAINT PINK (-7990 5350);
DISPLAY INVISIBLE (-7990 5350);
FORCEPROP 2 LAST CDS_XR_PAGE_TITLE CR-16 : @T6G_MB_LIB.T6G(SCH_1):PAGE16
J 0
(-7990 5350);
DISPLAY 0.638298 (-7990 5350);
PAINT PINK (-7990 5350);
DISPLAY INVISIBLE (-7990 5350);
FORCEPROP 1 LAST Q_DEPT BU9
J 1
(-3863 149);
DISPLAY 1.957447 (-3863 149);
PAINT GREEN (-3863 149);
DISPLAY INVISIBLE (-3863 149);
FORCEPROP 1 LAST COMMENT_BODY TRUE
J 0
(-88 87);
DISPLAY 0.978723 (-88 87);
PAINT GREEN (-88 87);
DISPLAY INVISIBLE (-88 87);
WIRE 17 -1 (-3375 5525)(-3375 5475);
WIRE 17 -1 (-3375 5575)(-3375 5525);
WIRE 17 -1 (-3375 5475)(-3375 5425);
WIRE 17 -1 (-3375 5425)(-3375 5375);
WIRE 17 -1 (-3375 5625)(-3375 5575);
WIRE 17 -1 (-3375 5725)(-3375 5625);
WIRE 17 -1 (-3375 5375)(-3375 5325);
WIRE 17 -1 (-3375 5325)(-3375 5275);
WIRE 17 -1 (-3375 5775)(-3375 5725);
WIRE 17 -1 (-3375 5825)(-3375 5775);
WIRE 17 -1 (-3375 5175)(-3375 5275);
WIRE 17 -1 (-3375 5125)(-3375 5175);
WIRE 17 -1 (-3375 5875)(-3375 5825);
WIRE 17 -1 (-3375 5925)(-3375 5875);
WIRE 17 -1 (-3375 5075)(-3375 5125);
WIRE 17 -1 (-3375 5025)(-3375 5075);
WIRE 17 -1 (-3375 5975)(-3375 5925);
WIRE 17 -1 (-3375 6025)(-3375 5975);
WIRE 17 -1 (-3375 5025)(-3375 4975);
WIRE 17 -1 (-3375 4975)(-3375 4925);
WIRE 17 -1 (-3375 6075)(-3375 6025);
WIRE 17 -1 (-3375 6075)(-2750 6075);
FORCEPROP 2 LAST SIG_NAME M_G_CPU0_SA_DQ<31:0>
J 2
(-2810 6085);
DISPLAY 0.489362 (-2810 6085);
WIRE 17 -1 (-3375 4925)(-3375 4875);
WIRE 17 -1 (-3375 4875)(-3375 4825);
WIRE 17 -1 (-3375 4825)(-3375 4725);
WIRE 17 -1 (-3375 4725)(-3375 4675);
WIRE 17 -1 (-3375 4675)(-3375 4625);
WIRE 17 -1 (-3375 4625)(-3375 4575);
WIRE 17 -1 (-3375 4525)(-3375 4575);
WIRE 17 -1 (-3375 4475)(-3375 4525);
WIRE 17 -1 (-3375 4425)(-3375 4475);
WIRE 17 -1 (-3375 4375)(-3375 4425);
WIRE 17 -1 (-3375 4275)(-3375 4225);
WIRE 17 -1 (-3375 4275)(-2750 4275);
FORCEPROP 2 LAST SIG_NAME M_G_CPU0_SB_DQ<31:0>
J 2
(-2810 4285);
DISPLAY 0.489362 (-2810 4285);
WIRE 17 -1 (-3375 4225)(-3375 4175);
WIRE 17 -1 (-3375 4175)(-3375 4125);
WIRE 17 -1 (-3375 4125)(-3375 4075);
WIRE 17 -1 (-3375 4075)(-3375 4025);
WIRE 17 -1 (-3375 4025)(-3375 3975);
WIRE 17 -1 (-3375 3975)(-3375 3925);
WIRE 17 -1 (-3375 3925)(-3375 3825);
WIRE 17 -1 (-3375 3225)(-3375 3175);
WIRE 17 -1 (-3375 3225)(-3375 3275);
WIRE 17 -1 (-3375 3175)(-3375 3125);
WIRE 17 -1 (-3375 3125)(-3375 3075);
WIRE 17 -1 (-3375 3275)(-3375 3325);
WIRE 17 -1 (-3375 3325)(-3375 3375);
WIRE 17 -1 (-3375 3075)(-3375 3025);
WIRE 17 -1 (-3375 3025)(-3375 2925);
WIRE 17 -1 (-3375 3375)(-3375 3475);
WIRE 17 -1 (-3375 3525)(-3375 3475);
WIRE 17 -1 (-3375 2925)(-3375 2875);
WIRE 17 -1 (-3375 2875)(-3375 2825);
WIRE 17 -1 (-3375 3575)(-3375 3525);
WIRE 17 -1 (-3375 3625)(-3375 3575);
WIRE 17 -1 (-3375 2825)(-3375 2775);
WIRE 17 -1 (-3375 2725)(-3375 2775);
WIRE 17 -1 (-3375 3675)(-3375 3625);
WIRE 17 -1 (-3375 3725)(-3375 3675);
WIRE 17 -1 (-3375 2675)(-3375 2725);
WIRE 17 -1 (-3375 2625)(-3375 2675);
WIRE 17 -1 (-3375 3775)(-3375 3725);
WIRE 17 -1 (-3375 3825)(-3375 3775);
WIRE 17 -1 (-3375 2575)(-3375 2625);
WIRE 17 -1 (-3375 2375)(-3375 2325);
WIRE 17 -1 (-3375 2375)(-3375 2425);
WIRE 17 -1 (-3375 2275)(-3375 2325);
WIRE 17 -1 (-3375 2225)(-3375 2275);
WIRE 17 -1 (-3375 2475)(-3375 2425);
WIRE 17 -1 (-3375 2475)(-3375 2500);
WIRE 17 -1 (-3375 2175)(-3375 2225);
WIRE 17 -1 (-3375 2125)(-3375 2175);
WIRE 17 -1 (-3375 2500)(-2875 2500);
FORCEPROP 2 LAST SIG_NAME M_G_CPU0_SA_CB<7:0>
J 2
(-2875 2510);
DISPLAY 0.489362 (-2875 2510);
WIRE 17 -1 (-3375 2025)(-3375 2050);
WIRE 17 -1 (-3375 2025)(-3375 1975);
WIRE 17 -1 (-3375 2050)(-2875 2050);
FORCEPROP 2 LAST SIG_NAME M_G_CPU0_SB_CB<7:0>
J 2
(-2875 2060);
DISPLAY 0.489362 (-2875 2060);
WIRE 17 -1 (-3375 1925)(-3375 1975);
WIRE 17 -1 (-3375 1925)(-3375 1875);
WIRE 17 -1 (-3375 1825)(-3375 1875);
WIRE 17 -1 (-3375 1775)(-3375 1825);
WIRE 17 -1 (-3375 1725)(-3375 1775);
WIRE 17 -1 (-3375 1675)(-3375 1725);
WIRE 17 -1 (-6100 6025)(-6100 5925);
FORCEPROP 2 LAST SIG_NAME M_G_CPU0_SA_DQS_DN<9:0>
J 2
(-6135 6035);
DISPLAY 0.489362 (-6135 6035);
WIRE 17 -1 (-6100 5925)(-6100 5825);
WIRE 17 -1 (-6100 5825)(-6100 5725);
WIRE 17 -1 (-6100 5725)(-6100 5625);
WIRE 17 -1 (-6100 5525)(-6100 5625);
WIRE 17 -1 (-6100 5425)(-6100 5525);
WIRE 17 -1 (-5900 6075)(-5900 5975);
WIRE 17 -1 (-5900 6075)(-6700 6075);
FORCEPROP 2 LAST SIG_NAME M_G_CPU0_SA_DQS_DP<9:0>
J 2
(-6135 6085);
DISPLAY 0.489362 (-6135 6085);
WIRE 17 -1 (-6100 5325)(-6100 5425);
WIRE 17 -1 (-6100 5325)(-6100 5225);
WIRE 17 -1 (-6100 5225)(-6100 5125);
WIRE 17 -1 (-5900 5975)(-5900 5875);
WIRE 17 -1 (-5900 5875)(-5900 5775);
WIRE 17 -1 (-5900 5775)(-5900 5675);
WIRE 17 -1 (-5900 5575)(-5900 5675);
WIRE 17 -1 (-5900 5475)(-5900 5575);
WIRE 17 -1 (-5900 5375)(-5900 5475);
WIRE 17 -1 (-5900 5375)(-5900 5275);
WIRE 17 -1 (-5900 5275)(-5900 5175);
WIRE 17 -1 (-5900 4525)(-5900 4625);
WIRE 17 -1 (-5900 4425)(-5900 4525);
WIRE 17 -1 (-5900 4725)(-5900 4625);
WIRE 17 -1 (-5900 4825)(-5900 4725);
WIRE 17 -1 (-5900 4325)(-5900 4425);
WIRE 17 -1 (-5900 4325)(-5900 4225);
WIRE 17 -1 (-5900 4925)(-5900 4825);
WIRE 17 -1 (-5900 5025)(-5900 4925);
WIRE 17 -1 (-5900 4225)(-5900 4125);
WIRE 17 -1 (-5900 5025)(-6700 5025);
FORCEPROP 2 LAST SIG_NAME M_G_CPU0_SB_DQS_DP<9:0>
J 2
(-6135 5035);
DISPLAY 0.489362 (-6135 5035);
WIRE 17 -1 (-6100 4975)(-6100 4875);
FORCEPROP 2 LAST SIG_NAME M_G_CPU0_SB_DQS_DN<9:0>
J 2
(-6135 4985);
DISPLAY 0.489362 (-6135 4985);
WIRE 17 -1 (-6100 4875)(-6100 4775);
WIRE 17 -1 (-6100 4775)(-6100 4675);
WIRE 17 -1 (-6100 4675)(-6100 4575);
WIRE 17 -1 (-6100 4475)(-6100 4575);
WIRE 17 -1 (-6100 4375)(-6100 4475);
WIRE 17 -1 (-6100 4275)(-6100 4375);
WIRE 17 -1 (-6100 4275)(-6100 4175);
WIRE 17 -1 (-6100 4175)(-6100 4075);
WIRE 17 -1 (-6100 3875)(-6100 3925);
WIRE 17 -1 (-6100 3825)(-6100 3875);
WIRE 17 -1 (-6100 3925)(-6600 3925);
FORCEPROP 2 LAST SIG_NAME M_G_CPU0_SA_CA<6:0>
J 0
(-6600 3935);
DISPLAY 0.489362 (-6600 3935);
WIRE 17 -1 (-6100 3475)(-6100 3525);
WIRE 17 -1 (-6100 3425)(-6100 3475);
WIRE 17 -1 (-6100 3525)(-6600 3525);
FORCEPROP 2 LAST SIG_NAME M_G_CPU0_SB_CA<6:0>
J 0
(-6600 3535);
DISPLAY 0.489362 (-6600 3535);
WIRE 17 -1 (-6100 3775)(-6100 3825);
WIRE 17 -1 (-6100 3375)(-6100 3425);
WIRE 17 -1 (-6100 3725)(-6100 3775);
WIRE 17 -1 (-6100 3675)(-6100 3725);
WIRE 17 -1 (-6100 3625)(-6100 3675);
WIRE 17 -1 (-6100 3325)(-6100 3375);
WIRE 17 -1 (-6100 3275)(-6100 3325);
WIRE 17 -1 (-6100 3225)(-6100 3275);
WIRE 17 -1 (-6100 6025)(-6700 6025);
WIRE 17 -1 (-6100 4975)(-6700 4975);
WIRE 16 -1 (-7800 2200)(-7075 2200);
FORCEPROP 2 LAST SIG_NAME M_G_CPU0_ALERT_N
J 0
(-7760 2210);
DISPLAY 0.489362 (-7760 2210);
WIRE 16 -1 (-6875 2200)(-5500 2200);
FORCEPROP 2 LAST SIG_NAME M_G_CPU0_ALERT_R_N
J 0
(-6585 2210);
DISPLAY 0.489362 (-6585 2210);
FORCEPROP 2 LASTPROP $XRERR UNIQUE?
J 0
(-6825 2210);
DISPLAY 0.638298 (-6825 2210);
PAINT MONO (-6825 2210);
DISPLAY INVISIBLE (-6825 2210);
WIRE 16 -1 (-6600 1250)(-5500 1250);
FORCEPROP 2 LAST SIG_NAME TP_M_G_CPU0_SA_TEST39G
J 0
(-6585 1260);
DISPLAY 0.489362 (-6585 1260);
FORCEPROP 2 LASTPROP $XRERR UNIQUE?
J 0
(-6840 1250);
DISPLAY 0.638298 (-6840 1250);
PAINT MONO (-6840 1250);
DISPLAY INVISIBLE (-6840 1250);
WIRE 16 -1 (-6600 3000)(-5500 3000);
FORCEPROP 2 LAST SIG_NAME M_G_CPU0_CLK_DN<0>
J 0
(-6600 3010);
DISPLAY 0.489362 (-6600 3010);
WIRE 16 -1 (-6600 3050)(-5500 3050);
FORCEPROP 2 LAST SIG_NAME M_G_CPU0_CLK_DP<0>
J 0
(-6600 3060);
DISPLAY 0.489362 (-6600 3060);
WIRE 16 -1 (-6600 2850)(-5500 2850);
FORCEPROP 2 LAST SIG_NAME M_G_CPU0_SA_CS_N<1>
J 0
(-6600 2860);
DISPLAY 0.489362 (-6600 2860);
WIRE 16 -1 (-6600 2900)(-5500 2900);
FORCEPROP 2 LAST SIG_NAME M_G_CPU0_SA_CS_N<0>
J 0
(-6600 2910);
DISPLAY 0.489362 (-6600 2910);
WIRE 16 -1 (-6600 2650)(-5500 2650);
FORCEPROP 2 LAST SIG_NAME M_G_CPU0_SA_PAR
J 0
(-6600 2660);
DISPLAY 0.489362 (-6600 2660);
WIRE 16 -1 (-6600 2750)(-5500 2750);
FORCEPROP 2 LAST SIG_NAME M_G_CPU0_SA_RSP<0>
J 0
(-6600 2760);
DISPLAY 0.489362 (-6600 2760);
WIRE 16 -1 (-6600 2400)(-5500 2400);
FORCEPROP 2 LAST SIG_NAME M_G_CPU0_SB_RSP<0>
J 0
(-6600 2410);
DISPLAY 0.489362 (-6600 2410);
WIRE 16 -1 (-6600 2550)(-5500 2550);
FORCEPROP 2 LAST SIG_NAME M_G_CPU0_SB_CS_N<0>
J 0
(-6600 2560);
DISPLAY 0.489362 (-6600 2560);
WIRE 16 -1 (-6600 2500)(-5500 2500);
FORCEPROP 2 LAST SIG_NAME M_G_CPU0_SB_CS_N<1>
J 0
(-6600 2510);
DISPLAY 0.489362 (-6600 2510);
WIRE 16 -1 (-6600 2300)(-5500 2300);
FORCEPROP 2 LAST SIG_NAME M_G_CPU0_SB_PAR
J 0
(-6600 2310);
DISPLAY 0.489362 (-6600 2310);
WIRE 16 -1 (-6600 2100)(-5500 2100);
FORCEPROP 2 LAST SIG_NAME M_G_CPU0_RESET_N
J 0
(-6600 2110);
DISPLAY 0.489362 (-6600 2110);
WIRE 16 -1 (-6000 3200)(-5500 3200);
WIRE 16 -1 (-6000 3600)(-5500 3600);
WIRE 16 -1 (-6000 3250)(-5500 3250);
WIRE 16 -1 (-6000 3650)(-5500 3650);
WIRE 16 -1 (-6000 3300)(-5500 3300);
WIRE 16 -1 (-6000 3700)(-5500 3700);
WIRE 16 -1 (-6000 3350)(-5500 3350);
WIRE 16 -1 (-6000 3750)(-5500 3750);
WIRE 16 -1 (-6000 3400)(-5500 3400);
WIRE 16 -1 (-6000 3800)(-5500 3800);
WIRE 16 -1 (-6000 3450)(-5500 3450);
WIRE 16 -1 (-6000 3850)(-5500 3850);
WIRE 16 -1 (-6000 3500)(-5500 3500);
WIRE 16 -1 (-6000 3900)(-5500 3900);
WIRE 16 -1 (-6000 4050)(-5500 4050);
WIRE 16 -1 (-5800 4100)(-5500 4100);
WIRE 16 -1 (-5800 4600)(-5500 4600);
WIRE 16 -1 (-6000 4150)(-5500 4150);
WIRE 16 -1 (-5800 4700)(-5500 4700);
WIRE 16 -1 (-6000 4250)(-5500 4250);
WIRE 16 -1 (-5800 4800)(-5500 4800);
WIRE 16 -1 (-6000 4350)(-5500 4350);
WIRE 16 -1 (-5800 4900)(-5500 4900);
WIRE 16 -1 (-6000 4450)(-5500 4450);
WIRE 16 -1 (-5800 5000)(-5500 5000);
WIRE 16 -1 (-6000 4550)(-5500 4550);
WIRE 16 -1 (-6000 5100)(-5500 5100);
WIRE 16 -1 (-6000 4650)(-5500 4650);
WIRE 16 -1 (-6000 4750)(-5500 4750);
WIRE 16 -1 (-6000 4850)(-5500 4850);
WIRE 16 -1 (-6000 4950)(-5500 4950);
WIRE 16 -1 (-5800 4200)(-5500 4200);
WIRE 16 -1 (-5800 4300)(-5500 4300);
WIRE 16 -1 (-5800 4400)(-5500 4400);
WIRE 16 -1 (-5800 4500)(-5500 4500);
WIRE 16 -1 (-5800 5150)(-5500 5150);
WIRE 16 -1 (-5800 5250)(-5500 5250);
WIRE 16 -1 (-5800 5350)(-5500 5350);
WIRE 16 -1 (-5800 5450)(-5500 5450);
WIRE 16 -1 (-5800 5550)(-5500 5550);
WIRE 16 -1 (-5800 5650)(-5500 5650);
WIRE 16 -1 (-6000 5200)(-5500 5200);
WIRE 16 -1 (-5800 5750)(-5500 5750);
WIRE 16 -1 (-6000 5300)(-5500 5300);
WIRE 16 -1 (-5800 5850)(-5500 5850);
WIRE 16 -1 (-6000 5400)(-5500 5400);
WIRE 16 -1 (-5800 5950)(-5500 5950);
WIRE 16 -1 (-6000 5500)(-5500 5500);
WIRE 16 -1 (-5800 6050)(-5500 6050);
WIRE 16 -1 (-6000 5600)(-5500 5600);
WIRE 16 -1 (-6000 5700)(-5500 5700);
WIRE 16 -1 (-6000 5800)(-5500 5800);
WIRE 16 -1 (-6000 5900)(-5500 5900);
WIRE 16 -1 (-6000 6000)(-5500 6000);
WIRE 16 -1 (-3900 1650)(-3475 1650);
WIRE 16 -1 (-3900 1700)(-3475 1700);
WIRE 16 -1 (-3900 1750)(-3475 1750);
WIRE 16 -1 (-3900 1800)(-3475 1800);
WIRE 16 -1 (-3900 1850)(-3475 1850);
WIRE 16 -1 (-3900 1900)(-3475 1900);
WIRE 16 -1 (-3900 1950)(-3475 1950);
WIRE 16 -1 (-3900 2000)(-3475 2000);
WIRE 16 -1 (-3900 2400)(-3475 2400);
WIRE 16 -1 (-3900 2450)(-3475 2450);
WIRE 16 -1 (-3900 2650)(-3475 2650);
WIRE 16 -1 (-3900 2700)(-3475 2700);
WIRE 16 -1 (-3900 2750)(-3475 2750);
WIRE 16 -1 (-3900 2800)(-3475 2800);
WIRE 16 -1 (-3900 2850)(-3475 2850);
WIRE 16 -1 (-3900 2900)(-3475 2900);
WIRE 16 -1 (-3900 3000)(-3475 3000);
WIRE 16 -1 (-3900 3050)(-3475 3050);
WIRE 16 -1 (-3900 2100)(-3475 2100);
WIRE 16 -1 (-3900 2150)(-3475 2150);
WIRE 16 -1 (-3900 2550)(-3475 2550);
WIRE 16 -1 (-3900 2200)(-3475 2200);
WIRE 16 -1 (-3900 2600)(-3475 2600);
WIRE 16 -1 (-3900 2250)(-3475 2250);
WIRE 16 -1 (-3900 2300)(-3475 2300);
WIRE 16 -1 (-3900 2350)(-3475 2350);
WIRE 16 -1 (-3900 3200)(-3475 3200);
WIRE 16 -1 (-3900 3250)(-3475 3250);
WIRE 16 -1 (-3900 3300)(-3475 3300);
WIRE 16 -1 (-3900 3350)(-3475 3350);
WIRE 16 -1 (-3900 3450)(-3475 3450);
WIRE 16 -1 (-3900 3500)(-3475 3500);
WIRE 16 -1 (-3900 3750)(-3475 3750);
WIRE 16 -1 (-3900 3550)(-3475 3550);
WIRE 16 -1 (-3900 3800)(-3475 3800);
WIRE 16 -1 (-3900 3600)(-3475 3600);
WIRE 16 -1 (-3900 3900)(-3475 3900);
WIRE 16 -1 (-3900 3650)(-3475 3650);
WIRE 16 -1 (-3900 3950)(-3475 3950);
WIRE 16 -1 (-3900 3700)(-3475 3700);
WIRE 16 -1 (-3900 3100)(-3475 3100);
WIRE 16 -1 (-3900 4000)(-3475 4000);
WIRE 16 -1 (-3900 3150)(-3475 3150);
WIRE 16 -1 (-3900 4050)(-3475 4050);
WIRE 16 -1 (-3900 4900)(-3475 4900);
WIRE 16 -1 (-3900 4250)(-3475 4250);
WIRE 16 -1 (-3900 4950)(-3475 4950);
WIRE 16 -1 (-3900 4350)(-3475 4350);
WIRE 16 -1 (-3900 4400)(-3475 4400);
WIRE 16 -1 (-3900 5000)(-3475 5000);
WIRE 16 -1 (-3900 5050)(-3475 5050);
WIRE 16 -1 (-3900 4450)(-3475 4450);
WIRE 16 -1 (-3900 5100)(-3475 5100);
WIRE 16 -1 (-3900 4500)(-3475 4500);
WIRE 16 -1 (-3900 4550)(-3475 4550);
WIRE 16 -1 (-3900 4600)(-3475 4600);
WIRE 16 -1 (-3900 4650)(-3475 4650);
WIRE 16 -1 (-3900 4700)(-3475 4700);
WIRE 16 -1 (-3900 4100)(-3475 4100);
WIRE 16 -1 (-3900 4800)(-3475 4800);
WIRE 16 -1 (-3900 4150)(-3475 4150);
WIRE 16 -1 (-3900 4850)(-3475 4850);
WIRE 16 -1 (-3900 4200)(-3475 4200);
WIRE 16 -1 (-3900 6050)(-3475 6050);
WIRE 16 -1 (-3900 5500)(-3475 5500);
WIRE 16 -1 (-3900 5550)(-3475 5550);
WIRE 16 -1 (-3900 5600)(-3475 5600);
WIRE 16 -1 (-3900 5700)(-3475 5700);
WIRE 16 -1 (-3900 5750)(-3475 5750);
WIRE 16 -1 (-3900 5150)(-3475 5150);
WIRE 16 -1 (-3900 5800)(-3475 5800);
WIRE 16 -1 (-3900 5250)(-3475 5250);
WIRE 16 -1 (-3900 5850)(-3475 5850);
WIRE 16 -1 (-3900 5300)(-3475 5300);
WIRE 16 -1 (-3900 5900)(-3475 5900);
WIRE 16 -1 (-3900 5350)(-3475 5350);
WIRE 16 -1 (-3900 5950)(-3475 5950);
WIRE 16 -1 (-3900 5400)(-3475 5400);
WIRE 16 -1 (-3900 6000)(-3475 6000);
WIRE 16 -1 (-3900 5450)(-3475 5450);
QUIT
